# Altium SchDoc records: FPGA.SchDoc
|HEADER=Protel for Windows - Schematic Capture Binary File Version 5.0|Weight=3307|MinorVersion=2
|RECORD=31|FontIdCount=5|Size1=10|FontName1=Times New Roman|Size2=12|FontName2=Arial|Size3=8|FontName3=Arial|Size4=10|FontName4=Arial|Size5=12|Underline5=T|FontName5=Arial|UseMBCS=T|IsBOC=T|HotSpotGridOn=T|HotSpotGridSize=1|SheetStyle=12|SystemFont=4|BorderOn=T|SheetNumberSpaceSize=12|AreaColor=16317695|SnapGridOn=T|SnapGridSize=1|VisibleGridOn=T|VisibleGridSize=10|CustomX=2338|CustomX_Frac=58268|CustomY=1653|CustomY_Frac=54331|CustomXZones=8|CustomYZones=6|CustomMarginWidth=19|CustomMarginWidth_Frac=80000|ShowTemplateGraphics=T|TemplateFileName=C:\Users\<user>\Documents\Altium\AD20\Templates\Timecard.SchDot|Display_Unit=0
|RECORD=39|IsNotAccesible=T|OwnerPartId=-1|FileName=C:\Users\<user>\Documents\Altium\AD20\Templates\Timecard.SchDot
|RECORD=4|OwnerIndex=1|OwnerPartId=-1|Location.X=1594|Location.Y=39|Color=8388608|FontID=5|Text=timingcard.com|URL=http://timingcard.com
|RECORD=6|OwnerIndex=1|IndexInSheet=1|OwnerPartId=-1|LocationCount=2|X1=1680|Y1=35|X2=1576|Y2=35
|RECORD=4|OwnerIndex=1|IndexInSheet=2|OwnerPartId=-1|Location.X=1614|Location.X_Frac=42446|Location.Y=19|Location.Y_Frac=96838|FontID=2|Text==SheetNumber
|RECORD=4|OwnerIndex=1|IndexInSheet=3|OwnerPartId=-1|Location.X=1581|Location.X_Frac=42446|Location.Y=29|Location.Y_Frac=96838|Justification=3|FontID=3|Text=SHEET
|RECORD=4|OwnerIndex=1|IndexInSheet=4|OwnerPartId=-1|Location.X=1639|Location.X_Frac=42446|Location.Y=29|Location.Y_Frac=96838|Justification=3|FontID=3|Text=OF
|RECORD=6|OwnerIndex=1|IndexInSheet=5|OwnerPartId=-1|LineWidth=1|LocationCount=2|X1=1679|X1_Frac=42446|Y1=105|Y1_Frac=96838|X2=1576|Y2=106
|RECORD=4|OwnerIndex=1|IndexInSheet=6|OwnerPartId=-1|Location.X=1658|Location.Y=20|FontID=2|Text==SheetTotal
|RECORD=30|OwnerIndex=1|IndexInSheet=7|OwnerPartId=-1|Location.X=1578|Location.Y=53|Corner.X=1673|Corner.X_Frac=88801|Corner.Y=103|KeepAspect=T|FileName=C:\Users\<user>\Desktop\Timecard Logo\TIMECARD.jpg
|RECORD=6|OwnerIndex=1|IndexInSheet=8|OwnerPartId=-1|LineWidth=1|LocationCount=2|X1=1576|X1_Frac=3162|Y1=105|Y1_Frac=42446|X2=1576|Y2=20
|RECORD=6|OwnerIndex=1|IndexInSheet=9|OwnerPartId=-1|LocationCount=2|X1=1680|Y1=51|X2=1576|Y2=51
|RECORD=41|IndexInSheet=1|OwnerPartId=-1|Color=8388608|FontID=1|IsHidden=T|Text=*|Name=CurrentTime|ReadOnlyState=1
|RECORD=41|IndexInSheet=2|OwnerPartId=-1|Color=8388608|FontID=1|IsHidden=T|Text=*|Name=CurrentDate|ReadOnlyState=1
|RECORD=41|IndexInSheet=3|OwnerPartId=-1|Color=8388608|FontID=1|IsHidden=T|Text=*|Name=Time|ReadOnlyState=1
|RECORD=41|IndexInSheet=4|OwnerPartId=-1|Color=8388608|FontID=1|IsHidden=T|Text=*|Name=Date|ReadOnlyState=1
|RECORD=41|IndexInSheet=5|OwnerPartId=-1|Color=8388608|FontID=1|IsHidden=T|Text=*|Name=DocumentFullPathAndName|ReadOnlyState=1
|RECORD=41|IndexInSheet=6|OwnerPartId=-1|Color=8388608|FontID=1|IsHidden=T|Text=*|Name=DocumentName|ReadOnlyState=1
|RECORD=41|IndexInSheet=7|OwnerPartId=-1|Color=8388608|FontID=1|IsHidden=T|Text=*|Name=ModifiedDate|ReadOnlyState=1
|RECORD=41|IndexInSheet=8|OwnerPartId=-1|Color=8388608|FontID=1|IsHidden=T|Text=*|Name=ApprovedBy|ReadOnlyState=1
|RECORD=41|IndexInSheet=9|OwnerPartId=-1|Color=8388608|FontID=1|IsHidden=T|Text=*|Name=CheckedBy|ReadOnlyState=1
|RECORD=41|IndexInSheet=10|OwnerPartId=-1|Color=8388608|FontID=1|IsHidden=T|Text=<name>|Name=Author|ReadOnlyState=1
|RECORD=41|IndexInSheet=11|OwnerPartId=-1|Color=8388608|FontID=1|IsHidden=T|Text=*|Name=CompanyName|ReadOnlyState=1
|RECORD=41|IndexInSheet=12|OwnerPartId=-1|Color=8388608|FontID=1|IsHidden=T|Text=*|Name=DrawnBy|ReadOnlyState=1
|RECORD=41|IndexInSheet=13|OwnerPartId=-1|Color=8388608|FontID=1|IsHidden=T|Text=*|Name=Engineer|ReadOnlyState=1
|RECORD=41|IndexInSheet=14|OwnerPartId=-1|Color=8388608|FontID=1|IsHidden=T|Text=*|Name=Organization|ReadOnlyState=1
|RECORD=41|IndexInSheet=15|OwnerPartId=-1|Color=8388608|FontID=1|IsHidden=T|Text=*|Name=Address1|ReadOnlyState=1
|RECORD=41|IndexInSheet=16|OwnerPartId=-1|Color=8388608|FontID=1|IsHidden=T|Text=*|Name=Address2|ReadOnlyState=1
|RECORD=41|IndexInSheet=17|OwnerPartId=-1|Color=8388608|FontID=1|IsHidden=T|Text=*|Name=Address3|ReadOnlyState=1
|RECORD=41|IndexInSheet=18|OwnerPartId=-1|Color=8388608|FontID=1|IsHidden=T|Text=*|Name=Address4|ReadOnlyState=1
|RECORD=41|IndexInSheet=19|OwnerPartId=-1|Color=8388608|FontID=1|IsHidden=T|Text=Grandmaster FPGA Connectors|Name=Title|ReadOnlyState=1
|RECORD=41|IndexInSheet=20|OwnerPartId=-1|Color=8388608|FontID=1|IsHidden=T|Text=*|Name=DocumentNumber|ReadOnlyState=1
|RECORD=41|IndexInSheet=21|OwnerPartId=-1|Color=8388608|FontID=1|IsHidden=T|Text=A|Name=Revision|ReadOnlyState=1
|RECORD=41|IndexInSheet=22|OwnerPartId=-1|Color=8388608|FontID=1|IsHidden=T|Text=7|Name=SheetNumber|ReadOnlyState=1
|RECORD=41|IndexInSheet=23|OwnerPartId=-1|Color=8388608|FontID=1|IsHidden=T|Text=7|Name=SheetTotal|ReadOnlyState=1
|RECORD=41|IndexInSheet=24|OwnerPartId=-1|Color=8388608|FontID=1|IsHidden=T|Text=*|Name=Rule|ReadOnlyState=1
|RECORD=41|IndexInSheet=25|OwnerPartId=-1|Color=8388608|FontID=1|IsHidden=T|Text=*|Name=ImagePath|ReadOnlyState=1
|RECORD=41|IndexInSheet=26|OwnerPartId=-1|Color=8388608|FontID=1|IsHidden=T|Text=*|Name=ProjectName|ReadOnlyState=1
|RECORD=41|IndexInSheet=27|OwnerPartId=-1|Color=8388608|FontID=1|IsHidden=T|Text=*|Name=Application_BuildNumber|ReadOnlyState=1
|RECORD=41|IndexInSheet=28|OwnerPartId=-1|Location.X=21474|Location.X_Frac=83647|Location.Y=21464|Location.Y_Frac=83647|Color=8388608|FontID=1|IsHidden=T|Text=01910|Name=Customer
|RECORD=41|IndexInSheet=29|OwnerPartId=-1|Location.X=1000|Location.Y=10|Color=8388608|FontID=1|IsHidden=T|Text=*|Name=DocStatus
|RECORD=17|IndexInSheet=30|OwnerPartId=-1|ShowNetName=T|Location.X=410|Location.Y=1008|Orientation=1|Color=128|FontID=1|Text=+5.0V
|RECORD=22|IndexInSheet=31|OwnerPartId=-1|Location.X=460|Location.Y=938|Color=255|Orientation=1|Symbol=Thin Cross|IsActive=T|SuppressAll=T
|RECORD=22|IndexInSheet=32|OwnerPartId=-1|Location.X=460|Location.Y=928|Color=255|Orientation=1|Symbol=Thin Cross|IsActive=T|SuppressAll=T
|RECORD=22|IndexInSheet=33|OwnerPartId=-1|Location.X=460|Location.Y=918|Color=255|Orientation=1|Symbol=Thin Cross|IsActive=T|SuppressAll=T
|RECORD=22|IndexInSheet=34|OwnerPartId=-1|Location.X=460|Location.Y=908|Color=255|Orientation=1|Symbol=Thin Cross|IsActive=T|SuppressAll=T
|RECORD=22|IndexInSheet=35|OwnerPartId=-1|Location.X=460|Location.Y=718|Color=255|Orientation=1|Symbol=Thin Cross|IsActive=T|SuppressAll=T
|RECORD=22|IndexInSheet=36|OwnerPartId=-1|Location.X=460|Location.Y=708|Color=255|Orientation=1|Symbol=Thin Cross|IsActive=T|SuppressAll=T
|RECORD=22|IndexInSheet=37|OwnerPartId=-1|Location.X=460|Location.Y=598|Color=255|Orientation=1|Symbol=Thin Cross|IsActive=T|SuppressAll=T
|RECORD=17|IndexInSheet=38|OwnerPartId=-1|Style=4|ShowNetName=T|Location.X=410|Location.Y=568|Orientation=3|Color=128|FontID=1|Text=GND
|RECORD=17|IndexInSheet=39|OwnerPartId=-1|ShowNetName=T|Location.X=330|Location.Y=658|Orientation=2|Color=255|FontID=1|Text=KEY2|IsCrossSheetConnector=T
|RECORD=17|IndexInSheet=40|OwnerPartId=-1|ShowNetName=T|Location.X=330|Location.Y=638|Orientation=2|Color=255|FontID=1|Text=LED4|IsCrossSheetConnector=T
|RECORD=17|IndexInSheet=41|OwnerPartId=-1|ShowNetName=T|Location.X=330|Location.Y=628|Orientation=2|Color=255|FontID=1|Text=LED3|IsCrossSheetConnector=T
|RECORD=17|IndexInSheet=42|OwnerPartId=-1|ShowNetName=T|Location.X=330|Location.Y=618|Orientation=2|Color=255|FontID=1|Text=LED2|IsCrossSheetConnector=T
|RECORD=17|IndexInSheet=43|OwnerPartId=-1|ShowNetName=T|Location.X=330|Location.Y=608|Orientation=2|Color=255|FontID=1|Text=LED1|IsCrossSheetConnector=T
|RECORD=17|IndexInSheet=44|OwnerPartId=-1|ShowNetName=T|Location.X=330|Location.Y=858|Orientation=2|Color=255|FontID=1|Text=CSN|IsCrossSheetConnector=T
|RECORD=17|IndexInSheet=45|OwnerPartId=-1|ShowNetName=T|Location.X=330|Location.Y=878|Orientation=2|Color=255|FontID=1|Text=MISO|IsCrossSheetConnector=T
|RECORD=17|IndexInSheet=46|OwnerPartId=-1|ShowNetName=T|Location.X=330|Location.Y=888|Orientation=2|Color=255|FontID=1|Text=MOSI|IsCrossSheetConnector=T
|RECORD=17|IndexInSheet=47|OwnerPartId=-1|ShowNetName=T|Location.X=330|Location.Y=868|Orientation=2|Color=255|FontID=1|Text=SCK|IsCrossSheetConnector=T
|RECORD=17|IndexInSheet=48|OwnerPartId=-1|ShowNetName=T|Location.X=330|Location.Y=818|Orientation=2|Color=255|FontID=1|Text=GPS2_RST|IsCrossSheetConnector=T
|RECORD=17|IndexInSheet=49|OwnerPartId=-1|ShowNetName=T|Location.X=330|Location.Y=768|Orientation=2|Color=255|FontID=1|Text=GPS2_TP2|IsCrossSheetConnector=T
|RECORD=17|IndexInSheet=50|OwnerPartId=-1|ShowNetName=T|Location.X=330|Location.Y=778|Orientation=2|Color=255|FontID=1|Text=GPS2_TP1|IsCrossSheetConnector=T
|RECORD=17|IndexInSheet=51|OwnerPartId=-1|ShowNetName=T|Location.X=600|Location.Y=1008|Orientation=1|Color=128|FontID=1|Text=+5.0V
|RECORD=22|IndexInSheet=52|OwnerPartId=-1|Location.X=580|Location.Y=938|Color=255|Orientation=1|Symbol=Thin Cross|IsActive=T|SuppressAll=T
|RECORD=22|IndexInSheet=53|OwnerPartId=-1|Location.X=580|Location.Y=928|Color=255|Orientation=1|Symbol=Thin Cross|IsActive=T|SuppressAll=T
|RECORD=22|IndexInSheet=54|OwnerPartId=-1|Location.X=580|Location.Y=738|Color=255|Orientation=1|Symbol=Thin Cross|IsActive=T|SuppressAll=T
|RECORD=22|IndexInSheet=55|OwnerPartId=-1|Location.X=580|Location.Y=668|Color=255|Orientation=1|Symbol=Thin Cross|IsActive=T|SuppressAll=T
|RECORD=22|IndexInSheet=56|OwnerPartId=-1|Location.X=580|Location.Y=658|Color=255|Orientation=1|Symbol=Thin Cross|IsActive=T|SuppressAll=T
|RECORD=22|IndexInSheet=57|OwnerPartId=-1|Location.X=580|Location.Y=638|Color=255|Orientation=1|Symbol=Thin Cross|IsActive=T|SuppressAll=T
|RECORD=22|IndexInSheet=58|OwnerPartId=-1|Location.X=580|Location.Y=628|Color=255|Orientation=1|Symbol=Thin Cross|IsActive=T|SuppressAll=T
|RECORD=22|IndexInSheet=59|OwnerPartId=-1|Location.X=580|Location.Y=618|Color=255|Orientation=1|Symbol=Thin Cross|IsActive=T|SuppressAll=T
|RECORD=22|IndexInSheet=60|OwnerPartId=-1|Location.X=580|Location.Y=608|Color=255|Orientation=1|Symbol=Thin Cross|IsActive=T|SuppressAll=T
|RECORD=22|IndexInSheet=61|OwnerPartId=-1|Location.X=580|Location.Y=598|Color=255|Orientation=1|Symbol=Thin Cross|IsActive=T|SuppressAll=T
|RECORD=17|IndexInSheet=62|OwnerPartId=-1|Style=4|ShowNetName=T|Location.X=600|Location.Y=568|Orientation=3|Color=128|FontID=1|Text=GND
|RECORD=17|IndexInSheet=63|OwnerPartId=-1|ShowNetName=T|Location.X=640|Location.Y=888|Color=255|FontID=1|Text=GPS1_RST|IsCrossSheetConnector=T
|RECORD=17|IndexInSheet=64|OwnerPartId=-1|ShowNetName=T|Location.X=640|Location.Y=838|Color=255|FontID=1|Text=GPS1_TP1|IsCrossSheetConnector=T
|RECORD=17|IndexInSheet=65|OwnerPartId=-1|ShowNetName=T|Location.X=640|Location.Y=828|Color=255|FontID=1|Text=GPS1_TP2|IsCrossSheetConnector=T
|RECORD=17|IndexInSheet=66|OwnerPartId=-1|ShowNetName=T|Location.X=640|Location.Y=688|Color=255|FontID=1|Text=IMU_BOOT|IsCrossSheetConnector=T
|RECORD=17|IndexInSheet=67|OwnerPartId=-1|ShowNetName=T|Location.X=640|Location.Y=678|Color=255|FontID=1|Text=IMU_CLKSEL0|IsCrossSheetConnector=T
|RECORD=17|IndexInSheet=68|OwnerPartId=-1|ShowNetName=T|Location.X=640|Location.Y=768|Color=255|FontID=1|Text=IMU_INT|IsCrossSheetConnector=T
|RECORD=17|IndexInSheet=69|OwnerPartId=-1|ShowNetName=T|Location.X=640|Location.Y=758|Color=255|FontID=1|Text=IMU_NRST|IsCrossSheetConnector=T
|RECORD=17|IndexInSheet=70|OwnerPartId=-1|ShowNetName=T|Location.X=640|Location.Y=728|Color=255|FontID=1|Text=IMU_PS0|IsCrossSheetConnector=T
|RECORD=17|IndexInSheet=71|OwnerPartId=-1|ShowNetName=T|Location.X=640|Location.Y=718|Color=255|FontID=1|Text=IMU_PS1|IsCrossSheetConnector=T
|RECORD=17|IndexInSheet=72|OwnerPartId=-1|Style=4|ShowNetName=T|Location.X=1130|Location.Y=568|Orientation=3|Color=128|FontID=1|Text=GND
|RECORD=17|IndexInSheet=73|OwnerPartId=-1|ShowNetName=T|Location.X=1060|Location.Y=608|Orientation=2|Color=255|FontID=1|Text=UART1_RXD|IsCrossSheetConnector=T
|RECORD=17|IndexInSheet=74|OwnerPartId=-1|ShowNetName=T|Location.X=1060|Location.Y=638|Orientation=2|Color=255|FontID=1|Text=UART1_TXD|IsCrossSheetConnector=T
|RECORD=17|IndexInSheet=75|OwnerPartId=-1|ShowNetName=T|Location.X=1060|Location.Y=598|Orientation=2|Color=255|FontID=1|Text=GPS1_RX|IsCrossSheetConnector=T
|RECORD=17|IndexInSheet=76|OwnerPartId=-1|ShowNetName=T|Location.X=1060|Location.Y=818|Orientation=2|Color=255|FontID=1|Text=MAC_ALARM|IsCrossSheetConnector=T
|RECORD=17|IndexInSheet=77|OwnerPartId=-1|ShowNetName=T|Location.X=1060|Location.Y=808|Orientation=2|Color=255|FontID=1|Text=MAC_BITE|IsCrossSheetConnector=T
|RECORD=17|IndexInSheet=78|OwnerPartId=-1|ShowNetName=T|Location.X=1060|Location.Y=828|Orientation=2|Color=255|FontID=1|Text=MAC_FREQ_CTRL|IsCrossSheetConnector=T
|RECORD=17|IndexInSheet=79|OwnerPartId=-1|ShowNetName=T|Location.X=1060|Location.Y=768|Orientation=2|Color=255|FontID=1|Text=MAC_PPS_IN0+|IsCrossSheetConnector=T
|RECORD=17|IndexInSheet=80|OwnerPartId=-1|ShowNetName=T|Location.X=1060|Location.Y=758|Orientation=2|Color=255|FontID=1|Text=MAC_PPS_IN0-|IsCrossSheetConnector=T
|RECORD=17|IndexInSheet=81|OwnerPartId=-1|ShowNetName=T|Location.X=1060|Location.Y=738|Orientation=2|Color=255|FontID=1|Text=MAC_PPS_IN1+|IsCrossSheetConnector=T
|RECORD=17|IndexInSheet=82|OwnerPartId=-1|ShowNetName=T|Location.X=1060|Location.Y=728|Orientation=2|Color=255|FontID=1|Text=MAC_PPS_IN1-|IsCrossSheetConnector=T
|RECORD=17|IndexInSheet=83|OwnerPartId=-1|ShowNetName=T|Location.X=1060|Location.Y=788|Orientation=2|Color=255|FontID=1|Text=MAC_PPS_OUT+|IsCrossSheetConnector=T
|RECORD=17|IndexInSheet=84|OwnerPartId=-1|ShowNetName=T|Location.X=1060|Location.Y=778|Orientation=2|Color=255|FontID=1|Text=MAC_PPS_OUT-|IsCrossSheetConnector=T
|RECORD=17|IndexInSheet=85|OwnerPartId=-1|ShowNetName=T|Location.X=1060|Location.Y=938|Orientation=2|Color=255|FontID=1|Text=MAC_RF_OUT|IsCrossSheetConnector=T
|RECORD=17|IndexInSheet=86|OwnerPartId=-1|ShowNetName=T|Location.X=1060|Location.Y=888|Orientation=2|Color=255|FontID=1|Text=ANT1|IsCrossSheetConnector=T
|RECORD=17|IndexInSheet=87|OwnerPartId=-1|ShowNetName=T|Location.X=1060|Location.Y=878|Orientation=2|Color=255|FontID=1|Text=ANT2|IsCrossSheetConnector=T
|RECORD=17|IndexInSheet=88|OwnerPartId=-1|ShowNetName=T|Location.X=1060|Location.Y=868|Orientation=2|Color=255|FontID=1|Text=ANT3|IsCrossSheetConnector=T
|RECORD=17|IndexInSheet=89|OwnerPartId=-1|ShowNetName=T|Location.X=1060|Location.Y=858|Orientation=2|Color=255|FontID=1|Text=ANT4|IsCrossSheetConnector=T
|RECORD=17|IndexInSheet=90|OwnerPartId=-1|ShowNetName=T|Location.X=1060|Location.Y=688|Orientation=2|Color=255|FontID=1|Text=SDA|IsCrossSheetConnector=T
|RECORD=17|IndexInSheet=91|OwnerPartId=-1|ShowNetName=T|Location.X=1060|Location.Y=658|Orientation=2|Color=255|FontID=1|Text=SCL|IsCrossSheetConnector=T
|RECORD=17|IndexInSheet=92|OwnerPartId=-1|Style=4|ShowNetName=T|Location.X=1320|Location.Y=568|Orientation=3|Color=128|FontID=1|Text=GND
|RECORD=17|IndexInSheet=93|OwnerPartId=-1|ShowNetName=T|Location.X=1350|Location.Y=918|Color=255|FontID=1|Text=DCXO2|IsCrossSheetConnector=T
|RECORD=17|IndexInSheet=94|OwnerPartId=-1|ShowNetName=T|Location.X=1350|Location.Y=598|Color=255|FontID=1|Text=GPS1_TX|IsCrossSheetConnector=T
|RECORD=17|IndexInSheet=95|OwnerPartId=-1|ShowNetName=T|Location.X=1350|Location.Y=858|Color=255|FontID=1|Text=MAC_RX|IsCrossSheetConnector=T
|RECORD=17|IndexInSheet=96|OwnerPartId=-1|ShowNetName=T|Location.X=1350|Location.Y=868|Color=255|FontID=1|Text=MAC_TX|IsCrossSheetConnector=T
|RECORD=17|IndexInSheet=97|OwnerPartId=-1|ShowNetName=T|Location.X=1350|Location.Y=638|Color=255|FontID=1|Text=MAC_USB+|IsCrossSheetConnector=T
|RECORD=17|IndexInSheet=98|OwnerPartId=-1|ShowNetName=T|Location.X=1350|Location.Y=628|Color=255|FontID=1|Text=MAC_USB-|IsCrossSheetConnector=T
|RECORD=17|IndexInSheet=99|OwnerPartId=-1|ShowNetName=T|Location.X=1350|Location.Y=958|Color=255|FontID=1|Text=MAC_USB_PWR|IsCrossSheetConnector=T
|RECORD=17|IndexInSheet=100|OwnerPartId=-1|ShowNetName=T|Location.X=1350|Location.Y=968|Color=255|FontID=1|Text=OE_5356|IsCrossSheetConnector=T
|RECORD=17|IndexInSheet=101|OwnerPartId=-1|ShowNetName=T|Location.X=1350|Location.Y=828|Color=255|FontID=1|Text=DCXO1|IsCrossSheetConnector=T
|RECORD=17|IndexInSheet=102|OwnerPartId=-1|ShowNetName=T|Location.X=1350|Location.Y=678|Color=255|FontID=1|Text=5721_STATUS|IsCrossSheetConnector=T
|RECORD=17|IndexInSheet=103|OwnerPartId=-1|Style=4|ShowNetName=T|Location.X=400|Location.Y=68|Orientation=3|Color=128|FontID=1|Text=GND
|RECORD=22|IndexInSheet=104|OwnerPartId=-1|Location.X=460|Location.Y=128|Color=255|Orientation=1|Symbol=Thin Cross|IsActive=T|SuppressAll=T
|RECORD=17|IndexInSheet=105|OwnerPartId=-1|ShowNetName=T|Location.X=320|Location.Y=398|Orientation=2|Color=255|FontID=1|Text=PCIE_PERST|IsCrossSheetConnector=T
|RECORD=17|IndexInSheet=106|OwnerPartId=-1|ShowNetName=T|Location.X=320|Location.Y=388|Orientation=2|Color=255|FontID=1|Text=KEY1|IsCrossSheetConnector=T
|RECORD=17|IndexInSheet=107|OwnerPartId=-1|ShowNetName=T|Location.X=320|Location.Y=118|Orientation=2|Color=255|FontID=1|Text=FPGA_TCK|IsCrossSheetConnector=T
|RECORD=17|IndexInSheet=108|OwnerPartId=-1|ShowNetName=T|Location.X=320|Location.Y=108|Orientation=2|Color=255|FontID=1|Text=FPGA_TDO|IsCrossSheetConnector=T
|RECORD=17|IndexInSheet=109|OwnerPartId=-1|ShowNetName=T|Location.X=320|Location.Y=348|Orientation=2|Color=255|FontID=1|Text=IMU_ENV_SCL|IsCrossSheetConnector=T
|RECORD=17|IndexInSheet=110|OwnerPartId=-1|ShowNetName=T|Location.X=320|Location.Y=318|Orientation=2|Color=255|FontID=1|Text=IMU_ENV_SDA|IsCrossSheetConnector=T
|RECORD=17|IndexInSheet=111|OwnerPartId=-1|ShowNetName=T|Location.X=320|Location.Y=248|Orientation=2|Color=255|FontID=1|Text=RTC_MFP|IsCrossSheetConnector=T
|RECORD=17|IndexInSheet=112|OwnerPartId=-1|ShowNetName=T|Location.X=320|Location.Y=498|Orientation=2|Color=255|FontID=1|Text=GPS2_RX|IsCrossSheetConnector=T
|RECORD=17|IndexInSheet=113|OwnerPartId=-1|Style=4|ShowNetName=T|Location.X=620|Location.Y=68|Orientation=3|Color=128|FontID=1|Text=GND
|RECORD=22|IndexInSheet=114|OwnerPartId=-1|Location.X=580|Location.Y=128|Color=255|Orientation=1|Symbol=Thin Cross|IsActive=T|SuppressAll=T
|RECORD=17|IndexInSheet=115|OwnerPartId=-1|ShowNetName=T|Location.X=690|Location.Y=118|Color=255|FontID=1|Text=FPGA_TDI|IsCrossSheetConnector=T
|RECORD=17|IndexInSheet=116|OwnerPartId=-1|ShowNetName=T|Location.X=690|Location.Y=108|Color=255|FontID=1|Text=FPGA_TMS|IsCrossSheetConnector=T
|RECORD=17|IndexInSheet=117|OwnerPartId=-1|ShowNetName=T|Location.X=690|Location.Y=498|Color=255|FontID=1|Text=GPS2_TX|IsCrossSheetConnector=T
|RECORD=22|IndexInSheet=118|OwnerPartId=-1|Location.X=1160|Location.Y=498|Color=255|Orientation=1|Symbol=Thin Cross|IsActive=T|SuppressAll=T
|RECORD=22|IndexInSheet=119|OwnerPartId=-1|Location.X=1160|Location.Y=488|Color=255|Orientation=1|Symbol=Thin Cross|IsActive=T|SuppressAll=T
|RECORD=22|IndexInSheet=120|OwnerPartId=-1|Location.X=1160|Location.Y=478|Color=255|Orientation=1|Symbol=Thin Cross|IsActive=T|SuppressAll=T
|RECORD=22|IndexInSheet=121|OwnerPartId=-1|Location.X=1160|Location.Y=468|Color=255|Orientation=1|Symbol=Thin Cross|IsActive=T|SuppressAll=T
|RECORD=22|IndexInSheet=122|OwnerPartId=-1|Location.X=1160|Location.Y=448|Color=255|Orientation=1|Symbol=Thin Cross|IsActive=T|SuppressAll=T
|RECORD=22|IndexInSheet=123|OwnerPartId=-1|Location.X=1160|Location.Y=438|Color=255|Orientation=1|Symbol=Thin Cross|IsActive=T|SuppressAll=T
|RECORD=22|IndexInSheet=124|OwnerPartId=-1|Location.X=1160|Location.Y=108|Color=255|Orientation=1|Symbol=Thin Cross|IsActive=T|SuppressAll=T
|RECORD=17|IndexInSheet=125|OwnerPartId=-1|Style=4|ShowNetName=T|Location.X=1110|Location.Y=78|Orientation=3|Color=128|FontID=1|Text=GND
|RECORD=17|IndexInSheet=126|OwnerPartId=-1|ShowNetName=T|Location.X=1060|Location.Y=418|Orientation=2|Color=255|FontID=1|Text=PCIE_TX3_P|IsCrossSheetConnector=T
|RECORD=17|IndexInSheet=127|OwnerPartId=-1|ShowNetName=T|Location.X=1060|Location.Y=408|Orientation=2|Color=255|FontID=1|Text=PCIE_TX3_N|IsCrossSheetConnector=T
|RECORD=17|IndexInSheet=128|OwnerPartId=-1|ShowNetName=T|Location.X=1060|Location.Y=388|Orientation=2|Color=255|FontID=1|Text=PCIE_RX3_P|IsCrossSheetConnector=T
|RECORD=17|IndexInSheet=129|OwnerPartId=-1|ShowNetName=T|Location.X=1060|Location.Y=378|Orientation=2|Color=255|FontID=1|Text=PCIE_RX3_N|IsCrossSheetConnector=T
|RECORD=17|IndexInSheet=130|OwnerPartId=-1|ShowNetName=T|Location.X=1060|Location.Y=358|Orientation=2|Color=255|FontID=1|Text=PCIE_TX0_P|IsCrossSheetConnector=T
|RECORD=17|IndexInSheet=131|OwnerPartId=-1|ShowNetName=T|Location.X=1060|Location.Y=348|Orientation=2|Color=255|FontID=1|Text=PCIE_TX0_N|IsCrossSheetConnector=T
|RECORD=17|IndexInSheet=132|OwnerPartId=-1|ShowNetName=T|Location.X=1060|Location.Y=328|Orientation=2|Color=255|FontID=1|Text=PCIE_RX0_P|IsCrossSheetConnector=T
|RECORD=17|IndexInSheet=133|OwnerPartId=-1|ShowNetName=T|Location.X=1060|Location.Y=318|Orientation=2|Color=255|FontID=1|Text=PCIE_RX0_N|IsCrossSheetConnector=T
|RECORD=43|IndexInSheet=134|OwnerPartId=-1|Location.X=1070|Location.Y=418|Color=255|Name=DIFFPAIR
|RECORD=41|OwnerIndex=145|OwnerPartId=-1|Location.X=1070|Location.Y=418|Color=8388608|FontID=1|IsHidden=T|Text=True|Name=DifferentialPair
|RECORD=43|IndexInSheet=135|OwnerPartId=-1|Location.X=1070|Location.Y=408|Color=255|Name=DIFFPAIR
|RECORD=41|OwnerIndex=147|OwnerPartId=-1|Location.X=1070|Location.Y=408|Color=8388608|FontID=1|IsHidden=T|Text=True|Name=DifferentialPair
|RECORD=43|IndexInSheet=136|OwnerPartId=-1|Location.X=1070|Location.Y=388|Color=255|Name=DIFFPAIR
|RECORD=41|OwnerIndex=149|OwnerPartId=-1|Location.X=1070|Location.Y=388|Color=8388608|FontID=1|IsHidden=T|Text=True|Name=DifferentialPair
|RECORD=43|IndexInSheet=137|OwnerPartId=-1|Location.X=1070|Location.Y=378|Color=255|Name=DIFFPAIR
|RECORD=41|OwnerIndex=151|OwnerPartId=-1|Location.X=1070|Location.Y=378|Color=8388608|FontID=1|IsHidden=T|Text=True|Name=DifferentialPair
|RECORD=43|IndexInSheet=138|OwnerPartId=-1|Location.X=1070|Location.Y=358|Color=255|Name=DIFFPAIR
|RECORD=41|OwnerIndex=153|OwnerPartId=-1|Location.X=1070|Location.Y=358|Color=8388608|FontID=1|IsHidden=T|Text=True|Name=DifferentialPair
|RECORD=43|IndexInSheet=139|OwnerPartId=-1|Location.X=1070|Location.Y=348|Color=255|Name=DIFFPAIR
|RECORD=41|OwnerIndex=155|OwnerPartId=-1|Location.X=1070|Location.Y=348|Color=8388608|FontID=1|IsHidden=T|Text=True|Name=DifferentialPair
|RECORD=43|IndexInSheet=140|OwnerPartId=-1|Location.X=1070|Location.Y=328|Color=255|Name=DIFFPAIR
|RECORD=41|OwnerIndex=157|OwnerPartId=-1|Location.X=1070|Location.Y=328|Color=8388608|FontID=1|IsHidden=T|Text=True|Name=DifferentialPair
|RECORD=43|IndexInSheet=141|OwnerPartId=-1|Location.X=1070|Location.Y=318|Color=255|Name=DIFFPAIR
|RECORD=41|OwnerIndex=159|OwnerPartId=-1|Location.X=1070|Location.Y=318|Color=8388608|FontID=1|IsHidden=T|Text=True|Name=DifferentialPair
|RECORD=22|IndexInSheet=142|OwnerPartId=-1|Location.X=1280|Location.Y=498|Color=255|Orientation=1|Symbol=Thin Cross|IsActive=T|SuppressAll=T
|RECORD=22|IndexInSheet=143|OwnerPartId=-1|Location.X=1280|Location.Y=488|Color=255|Orientation=1|Symbol=Thin Cross|IsActive=T|SuppressAll=T
|RECORD=22|IndexInSheet=144|OwnerPartId=-1|Location.X=1280|Location.Y=478|Color=255|Orientation=1|Symbol=Thin Cross|IsActive=T|SuppressAll=T
|RECORD=22|IndexInSheet=145|OwnerPartId=-1|Location.X=1280|Location.Y=468|Color=255|Orientation=1|Symbol=Thin Cross|IsActive=T|SuppressAll=T
|RECORD=22|IndexInSheet=146|OwnerPartId=-1|Location.X=1280|Location.Y=108|Color=255|Orientation=1|Symbol=Thin Cross|IsActive=T|SuppressAll=T
|RECORD=17|IndexInSheet=147|OwnerPartId=-1|Style=4|ShowNetName=T|Location.X=1310|Location.Y=78|Orientation=3|Color=128|FontID=1|Text=GND
|RECORD=17|IndexInSheet=148|OwnerPartId=-1|ShowNetName=T|Location.X=1360|Location.Y=448|Color=255|FontID=1|Text=PCIE_TX2_P|IsCrossSheetConnector=T
|RECORD=17|IndexInSheet=149|OwnerPartId=-1|ShowNetName=T|Location.X=1360|Location.Y=438|Color=255|FontID=1|Text=PCIE_TX2_N|IsCrossSheetConnector=T
|RECORD=17|IndexInSheet=150|OwnerPartId=-1|ShowNetName=T|Location.X=1360|Location.Y=418|Color=255|FontID=1|Text=PCIE_RX2_P|IsCrossSheetConnector=T
|RECORD=17|IndexInSheet=151|OwnerPartId=-1|ShowNetName=T|Location.X=1360|Location.Y=408|Color=255|FontID=1|Text=PCIE_RX2_N|IsCrossSheetConnector=T
|RECORD=17|IndexInSheet=152|OwnerPartId=-1|ShowNetName=T|Location.X=1360|Location.Y=388|Color=255|FontID=1|Text=PCIE_TX1_P|IsCrossSheetConnector=T
|RECORD=17|IndexInSheet=153|OwnerPartId=-1|ShowNetName=T|Location.X=1360|Location.Y=378|Color=255|FontID=1|Text=PCIE_TX1_N|IsCrossSheetConnector=T
|RECORD=17|IndexInSheet=154|OwnerPartId=-1|ShowNetName=T|Location.X=1360|Location.Y=358|Color=255|FontID=1|Text=PCIE_RX1_P|IsCrossSheetConnector=T
|RECORD=17|IndexInSheet=155|OwnerPartId=-1|ShowNetName=T|Location.X=1360|Location.Y=348|Color=255|FontID=1|Text=PCIE_RX1_N|IsCrossSheetConnector=T
|RECORD=17|IndexInSheet=156|OwnerPartId=-1|ShowNetName=T|Location.X=1360|Location.Y=328|Color=255|FontID=1|Text=PCIE_CLK_P|IsCrossSheetConnector=T
|RECORD=17|IndexInSheet=157|OwnerPartId=-1|ShowNetName=T|Location.X=1360|Location.Y=318|Color=255|FontID=1|Text=PCIE_CLK_N|IsCrossSheetConnector=T
|RECORD=43|IndexInSheet=158|OwnerPartId=-1|Location.X=1330|Location.Y=448|Color=255|Name=DIFFPAIR
|RECORD=41|OwnerIndex=177|OwnerPartId=-1|Location.X=1330|Location.Y=448|Color=8388608|FontID=1|IsHidden=T|Text=True|Name=DifferentialPair
|RECORD=43|IndexInSheet=159|OwnerPartId=-1|Location.X=1330|Location.Y=438|Color=255|Name=DIFFPAIR
|RECORD=41|OwnerIndex=179|OwnerPartId=-1|Location.X=1330|Location.Y=438|Color=8388608|FontID=1|IsHidden=T|Text=True|Name=DifferentialPair
|RECORD=43|IndexInSheet=160|OwnerPartId=-1|Location.X=1330|Location.Y=418|Color=255|Name=DIFFPAIR
|RECORD=41|OwnerIndex=181|OwnerPartId=-1|Location.X=1330|Location.Y=418|Color=8388608|FontID=1|IsHidden=T|Text=True|Name=DifferentialPair
|RECORD=43|IndexInSheet=161|OwnerPartId=-1|Location.X=1330|Location.Y=408|Color=255|Name=DIFFPAIR
|RECORD=41|OwnerIndex=183|OwnerPartId=-1|Location.X=1330|Location.Y=408|Color=8388608|FontID=1|IsHidden=T|Text=True|Name=DifferentialPair
|RECORD=43|IndexInSheet=162|OwnerPartId=-1|Location.X=1330|Location.Y=388|Color=255|Name=DIFFPAIR
|RECORD=41|OwnerIndex=185|OwnerPartId=-1|Location.X=1330|Location.Y=388|Color=8388608|FontID=1|IsHidden=T|Text=True|Name=DifferentialPair
|RECORD=43|IndexInSheet=163|OwnerPartId=-1|Location.X=1330|Location.Y=378|Color=255|Name=DIFFPAIR
|RECORD=41|OwnerIndex=187|OwnerPartId=-1|Location.X=1330|Location.Y=378|Color=8388608|FontID=1|IsHidden=T|Text=True|Name=DifferentialPair
|RECORD=43|IndexInSheet=164|OwnerPartId=-1|Location.X=1330|Location.Y=358|Color=255|Name=DIFFPAIR
|RECORD=41|OwnerIndex=189|OwnerPartId=-1|Location.X=1330|Location.Y=358|Color=8388608|FontID=1|IsHidden=T|Text=True|Name=DifferentialPair
|RECORD=43|IndexInSheet=165|OwnerPartId=-1|Location.X=1330|Location.Y=348|Color=255|Name=DIFFPAIR
|RECORD=41|OwnerIndex=191|OwnerPartId=-1|Location.X=1330|Location.Y=348|Color=8388608|FontID=1|IsHidden=T|Text=True|Name=DifferentialPair
|RECORD=43|IndexInSheet=166|OwnerPartId=-1|Location.X=1330|Location.Y=328|Color=255|Name=DIFFPAIR
|RECORD=41|OwnerIndex=193|OwnerPartId=-1|Location.X=1330|Location.Y=328|Color=8388608|FontID=1|IsHidden=T|Text=True|Name=DifferentialPair
|RECORD=43|IndexInSheet=167|OwnerPartId=-1|Location.X=1330|Location.Y=318|Color=255|Name=DIFFPAIR
|RECORD=41|OwnerIndex=195|OwnerPartId=-1|Location.X=1330|Location.Y=318|Color=8388608|FontID=1|IsHidden=T|Text=True|Name=DifferentialPair
|RECORD=17|IndexInSheet=168|OwnerPartId=-1|ShowNetName=T|Location.X=960|Location.Y=748|Orientation=2|Color=255|FontID=1|Text=MAC_PPSin|IsCrossSheetConnector=T
|RECORD=17|IndexInSheet=169|OwnerPartId=-1|ShowNetName=T|Location.X=960|Location.Y=798|Orientation=2|Color=255|FontID=1|Text=MAC_PPSout|IsCrossSheetConnector=T
|RECORD=17|IndexInSheet=170|OwnerPartId=-1|ShowNetName=T|Location.X=960|Location.Y=838|Orientation=2|Color=255|FontID=1|Text=MAC_10Mout|IsCrossSheetConnector=T
|RECORD=22|IndexInSheet=171|OwnerPartId=-1|Location.X=460|Location.Y=838|Color=255|Orientation=1|Symbol=Thin Cross|IsActive=T|SuppressAll=T
|RECORD=22|IndexInSheet=172|OwnerPartId=-1|Location.X=460|Location.Y=828|Color=255|Orientation=1|Symbol=Thin Cross|IsActive=T|SuppressAll=T
|RECORD=22|IndexInSheet=173|OwnerPartId=-1|Location.X=460|Location.Y=808|Color=255|Orientation=1|Symbol=Thin Cross|IsActive=T|SuppressAll=T
|RECORD=22|IndexInSheet=174|OwnerPartId=-1|Location.X=460|Location.Y=788|Color=255|Orientation=1|Symbol=Thin Cross|IsActive=T|SuppressAll=T
|RECORD=22|IndexInSheet=175|OwnerPartId=-1|Location.X=460|Location.Y=758|Color=255|Orientation=1|Symbol=Thin Cross|IsActive=T|SuppressAll=T
|RECORD=22|IndexInSheet=176|OwnerPartId=-1|Location.X=460|Location.Y=738|Color=255|Orientation=1|Symbol=Thin Cross|IsActive=T|SuppressAll=T
|RECORD=22|IndexInSheet=177|OwnerPartId=-1|Location.X=460|Location.Y=728|Color=255|Orientation=1|Symbol=Thin Cross|IsActive=T|SuppressAll=T
|RECORD=22|IndexInSheet=178|OwnerPartId=-1|Location.X=460|Location.Y=688|Color=255|Orientation=1|Symbol=Thin Cross|IsActive=T|SuppressAll=T
|RECORD=22|IndexInSheet=179|OwnerPartId=-1|Location.X=460|Location.Y=678|Color=255|Orientation=1|Symbol=Thin Cross|IsActive=T|SuppressAll=T
|RECORD=22|IndexInSheet=180|OwnerPartId=-1|Location.X=460|Location.Y=668|Color=255|Orientation=1|Symbol=Thin Cross|IsActive=T|SuppressAll=T
|RECORD=22|IndexInSheet=181|OwnerPartId=-1|Location.X=460|Location.Y=588|Color=255|Orientation=1|Symbol=Thin Cross|IsActive=T|SuppressAll=T
|RECORD=22|IndexInSheet=182|OwnerPartId=-1|Location.X=460|Location.Y=578|Color=255|Orientation=1|Symbol=Thin Cross|IsActive=T|SuppressAll=T
|RECORD=22|IndexInSheet=183|OwnerPartId=-1|Location.X=580|Location.Y=588|Color=255|Orientation=1|Symbol=Thin Cross|IsActive=T|SuppressAll=T
|RECORD=22|IndexInSheet=184|OwnerPartId=-1|Location.X=580|Location.Y=578|Color=255|Orientation=1|Symbol=Thin Cross|IsActive=T|SuppressAll=T
|RECORD=22|IndexInSheet=185|OwnerPartId=-1|Location.X=580|Location.Y=708|Color=255|Orientation=1|Symbol=Thin Cross|IsActive=T|SuppressAll=T
|RECORD=22|IndexInSheet=186|OwnerPartId=-1|Location.X=580|Location.Y=788|Color=255|Orientation=1|Symbol=Thin Cross|IsActive=T|SuppressAll=T
|RECORD=22|IndexInSheet=187|OwnerPartId=-1|Location.X=580|Location.Y=808|Color=255|Orientation=1|Symbol=Thin Cross|IsActive=T|SuppressAll=T
|RECORD=22|IndexInSheet=188|OwnerPartId=-1|Location.X=580|Location.Y=818|Color=255|Orientation=1|Symbol=Thin Cross|IsActive=T|SuppressAll=T
|RECORD=22|IndexInSheet=189|OwnerPartId=-1|Location.X=580|Location.Y=858|Color=255|Orientation=1|Symbol=Thin Cross|IsActive=T|SuppressAll=T
|RECORD=22|IndexInSheet=190|OwnerPartId=-1|Location.X=580|Location.Y=868|Color=255|Orientation=1|Symbol=Thin Cross|IsActive=T|SuppressAll=T
|RECORD=22|IndexInSheet=191|OwnerPartId=-1|Location.X=580|Location.Y=878|Color=255|Orientation=1|Symbol=Thin Cross|IsActive=T|SuppressAll=T
|RECORD=22|IndexInSheet=192|OwnerPartId=-1|Location.X=580|Location.Y=908|Color=255|Orientation=1|Symbol=Thin Cross|IsActive=T|SuppressAll=T
|RECORD=22|IndexInSheet=193|OwnerPartId=-1|Location.X=580|Location.Y=918|Color=255|Orientation=1|Symbol=Thin Cross|IsActive=T|SuppressAll=T
|RECORD=22|IndexInSheet=194|OwnerPartId=-1|Location.X=1170|Location.Y=988|Color=255|Orientation=1|Symbol=Thin Cross|IsActive=T|SuppressAll=T
|RECORD=22|IndexInSheet=195|OwnerPartId=-1|Location.X=1170|Location.Y=968|Color=255|Orientation=1|Symbol=Thin Cross|IsActive=T|SuppressAll=T
|RECORD=22|IndexInSheet=196|OwnerPartId=-1|Location.X=1170|Location.Y=978|Color=255|Orientation=1|Symbol=Thin Cross|IsActive=T|SuppressAll=T
|RECORD=22|IndexInSheet=197|OwnerPartId=-1|Location.X=1170|Location.Y=958|Color=255|Orientation=1|Symbol=Thin Cross|IsActive=T|SuppressAll=T
|RECORD=22|IndexInSheet=198|OwnerPartId=-1|Location.X=1290|Location.Y=978|Color=255|Orientation=1|Symbol=Thin Cross|IsActive=T|SuppressAll=T
|RECORD=22|IndexInSheet=199|OwnerPartId=-1|Location.X=1290|Location.Y=988|Color=255|Orientation=1|Symbol=Thin Cross|IsActive=T|SuppressAll=T
|RECORD=22|IndexInSheet=200|OwnerPartId=-1|Location.X=1290|Location.Y=938|Color=255|Orientation=1|Symbol=Thin Cross|IsActive=T|SuppressAll=T
|RECORD=22|IndexInSheet=201|OwnerPartId=-1|Location.X=1290|Location.Y=928|Color=255|Orientation=1|Symbol=Thin Cross|IsActive=T|SuppressAll=T
|RECORD=22|IndexInSheet=202|OwnerPartId=-1|Location.X=1170|Location.Y=918|Color=255|Orientation=1|Symbol=Thin Cross|IsActive=T|SuppressAll=T
|RECORD=22|IndexInSheet=203|OwnerPartId=-1|Location.X=1170|Location.Y=908|Color=255|Orientation=1|Symbol=Thin Cross|IsActive=T|SuppressAll=T
|RECORD=22|IndexInSheet=204|OwnerPartId=-1|Location.X=1290|Location.Y=908|Color=255|Orientation=1|Symbol=Thin Cross|IsActive=T|SuppressAll=T
|RECORD=22|IndexInSheet=205|OwnerPartId=-1|Location.X=1290|Location.Y=888|Color=255|Orientation=1|Symbol=Thin Cross|IsActive=T|SuppressAll=T
|RECORD=22|IndexInSheet=206|OwnerPartId=-1|Location.X=1290|Location.Y=878|Color=255|Orientation=1|Symbol=Thin Cross|IsActive=T|SuppressAll=T
|RECORD=22|IndexInSheet=207|OwnerPartId=-1|Location.X=1170|Location.Y=838|Color=255|Orientation=1|Symbol=Thin Cross|IsActive=T|SuppressAll=T
|RECORD=22|IndexInSheet=208|OwnerPartId=-1|Location.X=1290|Location.Y=838|Color=255|Orientation=1|Symbol=Thin Cross|IsActive=T|SuppressAll=T
|RECORD=22|IndexInSheet=209|OwnerPartId=-1|Location.X=1290|Location.Y=818|Color=255|Orientation=1|Symbol=Thin Cross|IsActive=T|SuppressAll=T
|RECORD=22|IndexInSheet=210|OwnerPartId=-1|Location.X=1290|Location.Y=808|Color=255|Orientation=1|Symbol=Thin Cross|IsActive=T|SuppressAll=T
|RECORD=22|IndexInSheet=211|OwnerPartId=-1|Location.X=1290|Location.Y=788|Color=255|Orientation=1|Symbol=Thin Cross|IsActive=T|SuppressAll=T
|RECORD=22|IndexInSheet=212|OwnerPartId=-1|Location.X=1290|Location.Y=778|Color=255|Orientation=1|Symbol=Thin Cross|IsActive=T|SuppressAll=T
|RECORD=22|IndexInSheet=213|OwnerPartId=-1|Location.X=1290|Location.Y=778|Color=255|Orientation=1|Symbol=Thin Cross|IsActive=T|SuppressAll=T
|RECORD=22|IndexInSheet=214|OwnerPartId=-1|Location.X=1290|Location.Y=768|Color=255|Orientation=1|Symbol=Thin Cross|IsActive=T|SuppressAll=T
|RECORD=22|IndexInSheet=215|OwnerPartId=-1|Location.X=1290|Location.Y=758|Color=255|Orientation=1|Symbol=Thin Cross|IsActive=T|SuppressAll=T
|RECORD=22|IndexInSheet=216|OwnerPartId=-1|Location.X=1170|Location.Y=718|Color=255|Orientation=1|Symbol=Thin Cross|IsActive=T|SuppressAll=T
|RECORD=22|IndexInSheet=217|OwnerPartId=-1|Location.X=1170|Location.Y=708|Color=255|Orientation=1|Symbol=Thin Cross|IsActive=T|SuppressAll=T
|RECORD=22|IndexInSheet=218|OwnerPartId=-1|Location.X=1290|Location.Y=738|Color=255|Orientation=1|Symbol=Thin Cross|IsActive=T|SuppressAll=T
|RECORD=22|IndexInSheet=219|OwnerPartId=-1|Location.X=1290|Location.Y=728|Color=255|Orientation=1|Symbol=Thin Cross|IsActive=T|SuppressAll=T
|RECORD=22|IndexInSheet=220|OwnerPartId=-1|Location.X=1290|Location.Y=718|Color=255|Orientation=1|Symbol=Thin Cross|IsActive=T|SuppressAll=T
|RECORD=22|IndexInSheet=221|OwnerPartId=-1|Location.X=1290|Location.Y=708|Color=255|Orientation=1|Symbol=Thin Cross|IsActive=T|SuppressAll=T
|RECORD=22|IndexInSheet=222|OwnerPartId=-1|Location.X=1290|Location.Y=688|Color=255|Orientation=1|Symbol=Thin Cross|IsActive=T|SuppressAll=T
|RECORD=22|IndexInSheet=223|OwnerPartId=-1|Location.X=1290|Location.Y=668|Color=255|Orientation=1|Symbol=Thin Cross|IsActive=T|SuppressAll=T
|RECORD=22|IndexInSheet=224|OwnerPartId=-1|Location.X=1290|Location.Y=658|Color=255|Orientation=1|Symbol=Thin Cross|IsActive=T|SuppressAll=T
|RECORD=22|IndexInSheet=225|OwnerPartId=-1|Location.X=1170|Location.Y=678|Color=255|Orientation=1|Symbol=Thin Cross|IsActive=T|SuppressAll=T
|RECORD=22|IndexInSheet=226|OwnerPartId=-1|Location.X=1170|Location.Y=668|Color=255|Orientation=1|Symbol=Thin Cross|IsActive=T|SuppressAll=T
|RECORD=22|IndexInSheet=227|OwnerPartId=-1|Location.X=1170|Location.Y=628|Color=255|Orientation=1|Symbol=Thin Cross|IsActive=T|SuppressAll=T
|RECORD=22|IndexInSheet=228|OwnerPartId=-1|Location.X=1170|Location.Y=618|Color=255|Orientation=1|Symbol=Thin Cross|IsActive=T|SuppressAll=T
|RECORD=22|IndexInSheet=229|OwnerPartId=-1|Location.X=1290|Location.Y=618|Color=255|Orientation=1|Symbol=Thin Cross|IsActive=T|SuppressAll=T
|RECORD=22|IndexInSheet=230|OwnerPartId=-1|Location.X=1290|Location.Y=608|Color=255|Orientation=1|Symbol=Thin Cross|IsActive=T|SuppressAll=T
|RECORD=22|IndexInSheet=231|OwnerPartId=-1|Location.X=1290|Location.Y=588|Color=255|Orientation=1|Symbol=Thin Cross|IsActive=T|SuppressAll=T
|RECORD=22|IndexInSheet=232|OwnerPartId=-1|Location.X=1290|Location.Y=578|Color=255|Orientation=1|Symbol=Thin Cross|IsActive=T|SuppressAll=T
|RECORD=22|IndexInSheet=233|OwnerPartId=-1|Location.X=1170|Location.Y=588|Color=255|Orientation=1|Symbol=Thin Cross|IsActive=T|SuppressAll=T
|RECORD=22|IndexInSheet=234|OwnerPartId=-1|Location.X=1170|Location.Y=578|Color=255|Orientation=1|Symbol=Thin Cross|IsActive=T|SuppressAll=T
|RECORD=22|IndexInSheet=235|OwnerPartId=-1|Location.X=1280|Location.Y=428|Color=255|Orientation=1|Symbol=Thin Cross|IsActive=T|SuppressAll=T
|RECORD=22|IndexInSheet=236|OwnerPartId=-1|Location.X=1280|Location.Y=398|Color=255|Orientation=1|Symbol=Thin Cross|IsActive=T|SuppressAll=T
|RECORD=22|IndexInSheet=237|OwnerPartId=-1|Location.X=1280|Location.Y=368|Color=255|Orientation=1|Symbol=Thin Cross|IsActive=T|SuppressAll=T
|RECORD=22|IndexInSheet=238|OwnerPartId=-1|Location.X=1280|Location.Y=338|Color=255|Orientation=1|Symbol=Thin Cross|IsActive=T|SuppressAll=T
|RECORD=22|IndexInSheet=239|OwnerPartId=-1|Location.X=1280|Location.Y=298|Color=255|Orientation=1|Symbol=Thin Cross|IsActive=T|SuppressAll=T
|RECORD=22|IndexInSheet=240|OwnerPartId=-1|Location.X=1280|Location.Y=288|Color=255|Orientation=1|Symbol=Thin Cross|IsActive=T|SuppressAll=T
|RECORD=22|IndexInSheet=241|OwnerPartId=-1|Location.X=1280|Location.Y=278|Color=255|Orientation=1|Symbol=Thin Cross|IsActive=T|SuppressAll=T
|RECORD=22|IndexInSheet=242|OwnerPartId=-1|Location.X=1280|Location.Y=268|Color=255|Orientation=1|Symbol=Thin Cross|IsActive=T|SuppressAll=T
|RECORD=22|IndexInSheet=243|OwnerPartId=-1|Location.X=1160|Location.Y=298|Color=255|Orientation=1|Symbol=Thin Cross|IsActive=T|SuppressAll=T
|RECORD=22|IndexInSheet=244|OwnerPartId=-1|Location.X=1160|Location.Y=288|Color=255|Orientation=1|Symbol=Thin Cross|IsActive=T|SuppressAll=T
|RECORD=22|IndexInSheet=245|OwnerPartId=-1|Location.X=1160|Location.Y=278|Color=255|Orientation=1|Symbol=Thin Cross|IsActive=T|SuppressAll=T
|RECORD=22|IndexInSheet=246|OwnerPartId=-1|Location.X=1160|Location.Y=268|Color=255|Orientation=1|Symbol=Thin Cross|IsActive=T|SuppressAll=T
|RECORD=22|IndexInSheet=247|OwnerPartId=-1|Location.X=1160|Location.Y=248|Color=255|Orientation=1|Symbol=Thin Cross|IsActive=T|SuppressAll=T
|RECORD=22|IndexInSheet=248|OwnerPartId=-1|Location.X=1160|Location.Y=238|Color=255|Orientation=1|Symbol=Thin Cross|IsActive=T|SuppressAll=T
|RECORD=22|IndexInSheet=249|OwnerPartId=-1|Location.X=1160|Location.Y=228|Color=255|Orientation=1|Symbol=Thin Cross|IsActive=T|SuppressAll=T
|RECORD=22|IndexInSheet=250|OwnerPartId=-1|Location.X=1160|Location.Y=218|Color=255|Orientation=1|Symbol=Thin Cross|IsActive=T|SuppressAll=T
|RECORD=22|IndexInSheet=251|OwnerPartId=-1|Location.X=1280|Location.Y=218|Color=255|Orientation=1|Symbol=Thin Cross|IsActive=T|SuppressAll=T
|RECORD=22|IndexInSheet=252|OwnerPartId=-1|Location.X=1280|Location.Y=228|Color=255|Orientation=1|Symbol=Thin Cross|IsActive=T|SuppressAll=T
|RECORD=22|IndexInSheet=253|OwnerPartId=-1|Location.X=1280|Location.Y=238|Color=255|Orientation=1|Symbol=Thin Cross|IsActive=T|SuppressAll=T
|RECORD=22|IndexInSheet=254|OwnerPartId=-1|Location.X=1280|Location.Y=248|Color=255|Orientation=1|Symbol=Thin Cross|IsActive=T|SuppressAll=T
|RECORD=22|IndexInSheet=255|OwnerPartId=-1|Location.X=1280|Location.Y=198|Color=255|Orientation=1|Symbol=Thin Cross|IsActive=T|SuppressAll=T
|RECORD=22|IndexInSheet=256|OwnerPartId=-1|Location.X=1280|Location.Y=188|Color=255|Orientation=1|Symbol=Thin Cross|IsActive=T|SuppressAll=T
|RECORD=22|IndexInSheet=257|OwnerPartId=-1|Location.X=1280|Location.Y=178|Color=255|Orientation=1|Symbol=Thin Cross|IsActive=T|SuppressAll=T
|RECORD=22|IndexInSheet=258|OwnerPartId=-1|Location.X=1280|Location.Y=168|Color=255|Orientation=1|Symbol=Thin Cross|IsActive=T|SuppressAll=T
|RECORD=22|IndexInSheet=259|OwnerPartId=-1|Location.X=1160|Location.Y=198|Color=255|Orientation=1|Symbol=Thin Cross|IsActive=T|SuppressAll=T
|RECORD=22|IndexInSheet=260|OwnerPartId=-1|Location.X=1160|Location.Y=188|Color=255|Orientation=1|Symbol=Thin Cross|IsActive=T|SuppressAll=T
|RECORD=22|IndexInSheet=261|OwnerPartId=-1|Location.X=1160|Location.Y=178|Color=255|Orientation=1|Symbol=Thin Cross|IsActive=T|SuppressAll=T
|RECORD=22|IndexInSheet=262|OwnerPartId=-1|Location.X=1160|Location.Y=168|Color=255|Orientation=1|Symbol=Thin Cross|IsActive=T|SuppressAll=T
|RECORD=22|IndexInSheet=263|OwnerPartId=-1|Location.X=1160|Location.Y=148|Color=255|Orientation=1|Symbol=Thin Cross|IsActive=T|SuppressAll=T
|RECORD=22|IndexInSheet=264|OwnerPartId=-1|Location.X=1160|Location.Y=138|Color=255|Orientation=1|Symbol=Thin Cross|IsActive=T|SuppressAll=T
|RECORD=22|IndexInSheet=265|OwnerPartId=-1|Location.X=1160|Location.Y=118|Color=255|Orientation=1|Symbol=Thin Cross|IsActive=T|SuppressAll=T
|RECORD=22|IndexInSheet=266|OwnerPartId=-1|Location.X=1160|Location.Y=128|Color=255|Orientation=1|Symbol=Thin Cross|IsActive=T|SuppressAll=T
|RECORD=22|IndexInSheet=267|OwnerPartId=-1|Location.X=1160|Location.Y=98|Color=255|Orientation=1|Symbol=Thin Cross|IsActive=T|SuppressAll=T
|RECORD=22|IndexInSheet=268|OwnerPartId=-1|Location.X=1160|Location.Y=88|Color=255|Orientation=1|Symbol=Thin Cross|IsActive=T|SuppressAll=T
|RECORD=22|IndexInSheet=269|OwnerPartId=-1|Location.X=1280|Location.Y=88|Color=255|Orientation=1|Symbol=Thin Cross|IsActive=T|SuppressAll=T
|RECORD=22|IndexInSheet=270|OwnerPartId=-1|Location.X=1280|Location.Y=98|Color=255|Orientation=1|Symbol=Thin Cross|IsActive=T|SuppressAll=T
|RECORD=22|IndexInSheet=271|OwnerPartId=-1|Location.X=1280|Location.Y=118|Color=255|Orientation=1|Symbol=Thin Cross|IsActive=T|SuppressAll=T
|RECORD=22|IndexInSheet=272|OwnerPartId=-1|Location.X=1280|Location.Y=128|Color=255|Orientation=1|Symbol=Thin Cross|IsActive=T|SuppressAll=T
|RECORD=22|IndexInSheet=273|OwnerPartId=-1|Location.X=1280|Location.Y=138|Color=255|Orientation=1|Symbol=Thin Cross|IsActive=T|SuppressAll=T
|RECORD=22|IndexInSheet=274|OwnerPartId=-1|Location.X=1280|Location.Y=148|Color=255|Orientation=1|Symbol=Thin Cross|IsActive=T|SuppressAll=T
|RECORD=22|IndexInSheet=275|OwnerPartId=-1|Location.X=460|Location.Y=488|Color=255|Orientation=1|Symbol=Thin Cross|IsActive=T|SuppressAll=T
|RECORD=22|IndexInSheet=276|OwnerPartId=-1|Location.X=460|Location.Y=478|Color=255|Orientation=1|Symbol=Thin Cross|IsActive=T|SuppressAll=T
|RECORD=22|IndexInSheet=277|OwnerPartId=-1|Location.X=460|Location.Y=468|Color=255|Orientation=1|Symbol=Thin Cross|IsActive=T|SuppressAll=T
|RECORD=22|IndexInSheet=278|OwnerPartId=-1|Location.X=580|Location.Y=488|Color=255|Orientation=1|Symbol=Thin Cross|IsActive=T|SuppressAll=T
|RECORD=22|IndexInSheet=279|OwnerPartId=-1|Location.X=580|Location.Y=478|Color=255|Orientation=1|Symbol=Thin Cross|IsActive=T|SuppressAll=T
|RECORD=22|IndexInSheet=280|OwnerPartId=-1|Location.X=580|Location.Y=468|Color=255|Orientation=1|Symbol=Thin Cross|IsActive=T|SuppressAll=T
|RECORD=22|IndexInSheet=281|OwnerPartId=-1|Location.X=580|Location.Y=448|Color=255|Orientation=1|Symbol=Thin Cross|IsActive=T|SuppressAll=T
|RECORD=22|IndexInSheet=282|OwnerPartId=-1|Location.X=580|Location.Y=438|Color=255|Orientation=1|Symbol=Thin Cross|IsActive=T|SuppressAll=T
|RECORD=22|IndexInSheet=283|OwnerPartId=-1|Location.X=580|Location.Y=428|Color=255|Orientation=1|Symbol=Thin Cross|IsActive=T|SuppressAll=T
|RECORD=22|IndexInSheet=284|OwnerPartId=-1|Location.X=580|Location.Y=418|Color=255|Orientation=1|Symbol=Thin Cross|IsActive=T|SuppressAll=T
|RECORD=22|IndexInSheet=285|OwnerPartId=-1|Location.X=460|Location.Y=448|Color=255|Orientation=1|Symbol=Thin Cross|IsActive=T|SuppressAll=T
|RECORD=22|IndexInSheet=286|OwnerPartId=-1|Location.X=460|Location.Y=438|Color=255|Orientation=1|Symbol=Thin Cross|IsActive=T|SuppressAll=T
|RECORD=22|IndexInSheet=287|OwnerPartId=-1|Location.X=460|Location.Y=428|Color=255|Orientation=1|Symbol=Thin Cross|IsActive=T|SuppressAll=T
|RECORD=22|IndexInSheet=288|OwnerPartId=-1|Location.X=460|Location.Y=418|Color=255|Orientation=1|Symbol=Thin Cross|IsActive=T|SuppressAll=T
|RECORD=22|IndexInSheet=289|OwnerPartId=-1|Location.X=460|Location.Y=378|Color=255|Orientation=1|Symbol=Thin Cross|IsActive=T|SuppressAll=T
|RECORD=22|IndexInSheet=290|OwnerPartId=-1|Location.X=460|Location.Y=368|Color=255|Orientation=1|Symbol=Thin Cross|IsActive=T|SuppressAll=T
|RECORD=22|IndexInSheet=291|OwnerPartId=-1|Location.X=580|Location.Y=398|Color=255|Orientation=1|Symbol=Thin Cross|IsActive=T|SuppressAll=T
|RECORD=22|IndexInSheet=292|OwnerPartId=-1|Location.X=580|Location.Y=388|Color=255|Orientation=1|Symbol=Thin Cross|IsActive=T|SuppressAll=T
|RECORD=22|IndexInSheet=293|OwnerPartId=-1|Location.X=580|Location.Y=378|Color=255|Orientation=1|Symbol=Thin Cross|IsActive=T|SuppressAll=T
|RECORD=22|IndexInSheet=294|OwnerPartId=-1|Location.X=580|Location.Y=368|Color=255|Orientation=1|Symbol=Thin Cross|IsActive=T|SuppressAll=T
|RECORD=22|IndexInSheet=295|OwnerPartId=-1|Location.X=580|Location.Y=348|Color=255|Orientation=1|Symbol=Thin Cross|IsActive=T|SuppressAll=T
|RECORD=22|IndexInSheet=296|OwnerPartId=-1|Location.X=580|Location.Y=338|Color=255|Orientation=1|Symbol=Thin Cross|IsActive=T|SuppressAll=T
|RECORD=22|IndexInSheet=297|OwnerPartId=-1|Location.X=580|Location.Y=328|Color=255|Orientation=1|Symbol=Thin Cross|IsActive=T|SuppressAll=T
|RECORD=22|IndexInSheet=298|OwnerPartId=-1|Location.X=580|Location.Y=318|Color=255|Orientation=1|Symbol=Thin Cross|IsActive=T|SuppressAll=T
|RECORD=22|IndexInSheet=299|OwnerPartId=-1|Location.X=460|Location.Y=338|Color=255|Orientation=1|Symbol=Thin Cross|IsActive=T|SuppressAll=T
|RECORD=22|IndexInSheet=300|OwnerPartId=-1|Location.X=460|Location.Y=328|Color=255|Orientation=1|Symbol=Thin Cross|IsActive=T|SuppressAll=T
|RECORD=22|IndexInSheet=301|OwnerPartId=-1|Location.X=460|Location.Y=298|Color=255|Orientation=1|Symbol=Thin Cross|IsActive=T|SuppressAll=T
|RECORD=22|IndexInSheet=302|OwnerPartId=-1|Location.X=460|Location.Y=288|Color=255|Orientation=1|Symbol=Thin Cross|IsActive=T|SuppressAll=T
|RECORD=22|IndexInSheet=303|OwnerPartId=-1|Location.X=460|Location.Y=278|Color=255|Orientation=1|Symbol=Thin Cross|IsActive=T|SuppressAll=T
|RECORD=22|IndexInSheet=304|OwnerPartId=-1|Location.X=460|Location.Y=268|Color=255|Orientation=1|Symbol=Thin Cross|IsActive=T|SuppressAll=T
|RECORD=22|IndexInSheet=305|OwnerPartId=-1|Location.X=580|Location.Y=298|Color=255|Orientation=1|Symbol=Thin Cross|IsActive=T|SuppressAll=T
|RECORD=22|IndexInSheet=306|OwnerPartId=-1|Location.X=580|Location.Y=288|Color=255|Orientation=1|Symbol=Thin Cross|IsActive=T|SuppressAll=T
|RECORD=22|IndexInSheet=307|OwnerPartId=-1|Location.X=580|Location.Y=268|Color=255|Orientation=1|Symbol=Thin Cross|IsActive=T|SuppressAll=T
|RECORD=22|IndexInSheet=308|OwnerPartId=-1|Location.X=580|Location.Y=278|Color=255|Orientation=1|Symbol=Thin Cross|IsActive=T|SuppressAll=T
|RECORD=22|IndexInSheet=309|OwnerPartId=-1|Location.X=460|Location.Y=238|Color=255|Orientation=1|Symbol=Thin Cross|IsActive=T|SuppressAll=T
|RECORD=22|IndexInSheet=310|OwnerPartId=-1|Location.X=460|Location.Y=228|Color=255|Orientation=1|Symbol=Thin Cross|IsActive=T|SuppressAll=T
|RECORD=22|IndexInSheet=311|OwnerPartId=-1|Location.X=460|Location.Y=218|Color=255|Orientation=1|Symbol=Thin Cross|IsActive=T|SuppressAll=T
|RECORD=22|IndexInSheet=312|OwnerPartId=-1|Location.X=580|Location.Y=248|Color=255|Orientation=1|Symbol=Thin Cross|IsActive=T|SuppressAll=T
|RECORD=22|IndexInSheet=313|OwnerPartId=-1|Location.X=580|Location.Y=238|Color=255|Orientation=1|Symbol=Thin Cross|IsActive=T|SuppressAll=T
|RECORD=22|IndexInSheet=314|OwnerPartId=-1|Location.X=580|Location.Y=228|Color=255|Orientation=1|Symbol=Thin Cross|IsActive=T|SuppressAll=T
|RECORD=22|IndexInSheet=315|OwnerPartId=-1|Location.X=580|Location.Y=218|Color=255|Orientation=1|Symbol=Thin Cross|IsActive=T|SuppressAll=T
|RECORD=22|IndexInSheet=316|OwnerPartId=-1|Location.X=460|Location.Y=198|Color=255|Orientation=1|Symbol=Thin Cross|IsActive=T|SuppressAll=T
|RECORD=22|IndexInSheet=317|OwnerPartId=-1|Location.X=460|Location.Y=188|Color=255|Orientation=1|Symbol=Thin Cross|IsActive=T|SuppressAll=T
|RECORD=22|IndexInSheet=318|OwnerPartId=-1|Location.X=460|Location.Y=178|Color=255|Orientation=1|Symbol=Thin Cross|IsActive=T|SuppressAll=T
|RECORD=22|IndexInSheet=319|OwnerPartId=-1|Location.X=460|Location.Y=168|Color=255|Orientation=1|Symbol=Thin Cross|IsActive=T|SuppressAll=T
|RECORD=22|IndexInSheet=320|OwnerPartId=-1|Location.X=580|Location.Y=198|Color=255|Orientation=1|Symbol=Thin Cross|IsActive=T|SuppressAll=T
|RECORD=22|IndexInSheet=321|OwnerPartId=-1|Location.X=580|Location.Y=188|Color=255|Orientation=1|Symbol=Thin Cross|IsActive=T|SuppressAll=T
|RECORD=22|IndexInSheet=322|OwnerPartId=-1|Location.X=580|Location.Y=178|Color=255|Orientation=1|Symbol=Thin Cross|IsActive=T|SuppressAll=T
|RECORD=22|IndexInSheet=323|OwnerPartId=-1|Location.X=580|Location.Y=168|Color=255|Orientation=1|Symbol=Thin Cross|IsActive=T|SuppressAll=T
|RECORD=22|IndexInSheet=324|OwnerPartId=-1|Location.X=580|Location.Y=148|Color=255|Orientation=1|Symbol=Thin Cross|IsActive=T|SuppressAll=T
|RECORD=22|IndexInSheet=325|OwnerPartId=-1|Location.X=580|Location.Y=138|Color=255|Orientation=1|Symbol=Thin Cross|IsActive=T|SuppressAll=T
|RECORD=22|IndexInSheet=326|OwnerPartId=-1|Location.X=460|Location.Y=148|Color=255|Orientation=1|Symbol=Thin Cross|IsActive=T|SuppressAll=T
|RECORD=22|IndexInSheet=327|OwnerPartId=-1|Location.X=460|Location.Y=148|Color=255|Orientation=1|Symbol=Thin Cross|IsActive=T|SuppressAll=T
|RECORD=22|IndexInSheet=328|OwnerPartId=-1|Location.X=460|Location.Y=138|Color=255|Orientation=1|Symbol=Thin Cross|IsActive=T|SuppressAll=T
|RECORD=22|IndexInSheet=329|OwnerPartId=-1|Location.X=460|Location.Y=98|Color=255|Orientation=1|Symbol=Thin Cross|IsActive=T|SuppressAll=T
|RECORD=22|IndexInSheet=330|OwnerPartId=-1|Location.X=460|Location.Y=88|Color=255|Orientation=1|Symbol=Thin Cross|IsActive=T|SuppressAll=T
|RECORD=22|IndexInSheet=331|OwnerPartId=-1|Location.X=580|Location.Y=88|Color=255|Orientation=1|Symbol=Thin Cross|IsActive=T|SuppressAll=T
|RECORD=22|IndexInSheet=332|OwnerPartId=-1|Location.X=580|Location.Y=98|Color=255|Orientation=1|Symbol=Thin Cross|IsActive=T|SuppressAll=T
|RECORD=1|LibReference=FPGA_CONN|PartCount=5|DisplayModeCount=1|IndexInSheet=333|OwnerPartId=-1|Location.X=460|Location.Y=988|CurrentPartId=1|LibraryPath=*|SourceLibraryName=FPGA_CONN.SchLib|TargetFileName=*|AreaColor=11599871|Color=128|PartIDLocked=T|NotUseDBTableName=T|DesignItemId=FPGA_CONN|AllPinCount=336
|RECORD=14|OwnerIndex=362|IsNotAccesible=T|OwnerPartId=2|Location.X=490|Location.Y=568|Corner.X=550|Corner.Y=998|Color=128|AreaColor=11599871|IsSolid=T
|RECORD=2|OwnerIndex=362|OwnerPartId=2|FormalType=1|PinConglomerate=58|PinLength=30|Location.X=490|Location.Y=988|Name=1|Designator=B-1|PinPropagationDelay=0.000000E+000
|RECORD=2|OwnerIndex=362|OwnerPartId=2|FormalType=1|PinConglomerate=56|PinLength=30|Location.X=550|Location.Y=988|Name=2|Designator=B-2|PinPropagationDelay=0.000000E+000
|RECORD=2|OwnerIndex=362|OwnerPartId=2|FormalType=1|PinConglomerate=58|PinLength=30|Location.X=490|Location.Y=978|Name=3|Designator=B-3|PinPropagationDelay=0.000000E+000
|RECORD=2|OwnerIndex=362|OwnerPartId=2|FormalType=1|PinConglomerate=56|PinLength=30|Location.X=550|Location.Y=978|Name=4|Designator=B-4|PinPropagationDelay=0.000000E+000
|RECORD=2|OwnerIndex=362|OwnerPartId=2|FormalType=1|PinConglomerate=58|PinLength=30|Location.X=490|Location.Y=968|Name=5|Designator=B-5|PinPropagationDelay=0.000000E+000
|RECORD=2|OwnerIndex=362|OwnerPartId=2|FormalType=1|PinConglomerate=56|PinLength=30|Location.X=550|Location.Y=968|Name=6|Designator=B-6|PinPropagationDelay=0.000000E+000
|RECORD=2|OwnerIndex=362|OwnerPartId=2|FormalType=1|PinConglomerate=58|PinLength=30|Location.X=490|Location.Y=958|Name=7|Designator=B-7|PinPropagationDelay=0.000000E+000
|RECORD=2|OwnerIndex=362|OwnerPartId=2|FormalType=1|PinConglomerate=56|PinLength=30|Location.X=550|Location.Y=958|Name=8|Designator=B-8|PinPropagationDelay=0.000000E+000
|RECORD=2|OwnerIndex=362|OwnerPartId=2|FormalType=1|PinConglomerate=58|PinLength=30|Location.X=490|Location.Y=948|Name=9|Designator=B-9|PinPropagationDelay=0.000000E+000
|RECORD=2|OwnerIndex=362|OwnerPartId=2|FormalType=1|PinConglomerate=56|PinLength=30|Location.X=550|Location.Y=948|Name=10|Designator=B-10|PinPropagationDelay=0.000000E+000
|RECORD=2|OwnerIndex=362|OwnerPartId=2|FormalType=1|PinConglomerate=58|PinLength=30|Location.X=490|Location.Y=938|Name=11|Designator=B-11|PinPropagationDelay=0.000000E+000
|RECORD=2|OwnerIndex=362|OwnerPartId=2|FormalType=1|PinConglomerate=56|PinLength=30|Location.X=550|Location.Y=938|Name=12|Designator=B-12|PinPropagationDelay=0.000000E+000
|RECORD=2|OwnerIndex=362|OwnerPartId=2|FormalType=1|PinConglomerate=58|PinLength=30|Location.X=490|Location.Y=928|Name=13|Designator=B-13|PinPropagationDelay=0.000000E+000
|RECORD=2|OwnerIndex=362|OwnerPartId=2|FormalType=1|PinConglomerate=56|PinLength=30|Location.X=550|Location.Y=928|Name=14|Designator=B-14|PinPropagationDelay=0.000000E+000
|RECORD=2|OwnerIndex=362|OwnerPartId=2|FormalType=1|PinConglomerate=58|PinLength=30|Location.X=490|Location.Y=918|Name=15|Designator=B-15|PinPropagationDelay=0.000000E+000
|RECORD=2|OwnerIndex=362|OwnerPartId=2|FormalType=1|PinConglomerate=56|PinLength=30|Location.X=550|Location.Y=918|Name=16|Designator=B-16|PinPropagationDelay=0.000000E+000
|RECORD=2|OwnerIndex=362|OwnerPartId=2|FormalType=1|PinConglomerate=58|PinLength=30|Location.X=490|Location.Y=908|Name=17|Designator=B-17|PinPropagationDelay=0.000000E+000
|RECORD=2|OwnerIndex=362|OwnerPartId=2|FormalType=1|PinConglomerate=56|PinLength=30|Location.X=550|Location.Y=908|Name=18|Designator=B-18|PinPropagationDelay=0.000000E+000
|RECORD=2|OwnerIndex=362|OwnerPartId=2|FormalType=1|PinConglomerate=58|PinLength=30|Location.X=490|Location.Y=898|Name=19|Designator=B-19|PinPropagationDelay=0.000000E+000
|RECORD=2|OwnerIndex=362|OwnerPartId=2|FormalType=1|PinConglomerate=56|PinLength=30|Location.X=550|Location.Y=898|Name=20|Designator=B-20|PinPropagationDelay=0.000000E+000
|RECORD=2|OwnerIndex=362|OwnerPartId=2|FormalType=1|PinConglomerate=58|PinLength=30|Location.X=490|Location.Y=888|Name=21|Designator=B-21|PinPropagationDelay=0.000000E+000
|RECORD=2|OwnerIndex=362|OwnerPartId=2|FormalType=1|PinConglomerate=56|PinLength=30|Location.X=550|Location.Y=888|Name=22|Designator=B-22|PinPropagationDelay=0.000000E+000
|RECORD=2|OwnerIndex=362|OwnerPartId=2|FormalType=1|PinConglomerate=58|PinLength=30|Location.X=490|Location.Y=878|Name=23|Designator=B-23|PinPropagationDelay=0.000000E+000
|RECORD=2|OwnerIndex=362|OwnerPartId=2|FormalType=1|PinConglomerate=56|PinLength=30|Location.X=550|Location.Y=878|Name=24|Designator=B-24|PinPropagationDelay=0.000000E+000
|RECORD=2|OwnerIndex=362|OwnerPartId=2|FormalType=1|PinConglomerate=58|PinLength=30|Location.X=490|Location.Y=868|Name=25|Designator=B-25|PinPropagationDelay=0.000000E+000
|RECORD=2|OwnerIndex=362|OwnerPartId=2|FormalType=1|PinConglomerate=56|PinLength=30|Location.X=550|Location.Y=868|Name=26|Designator=B-26|PinPropagationDelay=0.000000E+000
|RECORD=2|OwnerIndex=362|OwnerPartId=2|FormalType=1|PinConglomerate=58|PinLength=30|Location.X=490|Location.Y=858|Name=27|Designator=B-27|PinPropagationDelay=0.000000E+000
|RECORD=2|OwnerIndex=362|OwnerPartId=2|FormalType=1|PinConglomerate=56|PinLength=30|Location.X=550|Location.Y=858|Name=28|Designator=B-28|PinPropagationDelay=0.000000E+000
|RECORD=2|OwnerIndex=362|OwnerPartId=2|FormalType=1|PinConglomerate=58|PinLength=30|Location.X=490|Location.Y=848|Name=29|Designator=B-29|PinPropagationDelay=0.000000E+000
|RECORD=2|OwnerIndex=362|OwnerPartId=2|FormalType=1|PinConglomerate=56|PinLength=30|Location.X=550|Location.Y=848|Name=30|Designator=B-30|PinPropagationDelay=0.000000E+000
|RECORD=2|OwnerIndex=362|OwnerPartId=2|FormalType=1|PinConglomerate=58|PinLength=30|Location.X=490|Location.Y=838|Name=31|Designator=B-31|PinPropagationDelay=0.000000E+000
|RECORD=2|OwnerIndex=362|OwnerPartId=2|FormalType=1|PinConglomerate=56|PinLength=30|Location.X=550|Location.Y=838|Name=32|Designator=B-32|PinPropagationDelay=0.000000E+000
|RECORD=2|OwnerIndex=362|OwnerPartId=2|FormalType=1|PinConglomerate=58|PinLength=30|Location.X=490|Location.Y=828|Name=33|Designator=B-33|PinPropagationDelay=0.000000E+000
|RECORD=2|OwnerIndex=362|OwnerPartId=2|FormalType=1|PinConglomerate=56|PinLength=30|Location.X=550|Location.Y=828|Name=34|Designator=B-34|PinPropagationDelay=0.000000E+000
|RECORD=2|OwnerIndex=362|OwnerPartId=2|FormalType=1|PinConglomerate=58|PinLength=30|Location.X=490|Location.Y=818|Name=35|Designator=B-35|PinPropagationDelay=0.000000E+000
|RECORD=2|OwnerIndex=362|OwnerPartId=2|FormalType=1|PinConglomerate=56|PinLength=30|Location.X=550|Location.Y=818|Name=36|Designator=B-36|PinPropagationDelay=0.000000E+000
|RECORD=2|OwnerIndex=362|OwnerPartId=2|FormalType=1|PinConglomerate=58|PinLength=30|Location.X=490|Location.Y=808|Name=37|Designator=B-37|PinPropagationDelay=0.000000E+000
|RECORD=2|OwnerIndex=362|OwnerPartId=2|FormalType=1|PinConglomerate=56|PinLength=30|Location.X=550|Location.Y=808|Name=38|Designator=B-38|PinPropagationDelay=0.000000E+000
|RECORD=2|OwnerIndex=362|OwnerPartId=2|FormalType=1|PinConglomerate=58|PinLength=30|Location.X=490|Location.Y=798|Name=39|Designator=B-39|PinPropagationDelay=0.000000E+000
|RECORD=2|OwnerIndex=362|OwnerPartId=2|FormalType=1|PinConglomerate=56|PinLength=30|Location.X=550|Location.Y=798|Name=40|Designator=B-40|PinPropagationDelay=0.000000E+000
|RECORD=2|OwnerIndex=362|OwnerPartId=2|FormalType=1|PinConglomerate=58|PinLength=30|Location.X=490|Location.Y=788|Name=41|Designator=B-41|PinPropagationDelay=0.000000E+000
|RECORD=2|OwnerIndex=362|OwnerPartId=2|FormalType=1|PinConglomerate=56|PinLength=30|Location.X=550|Location.Y=788|Name=42|Designator=B-42|PinPropagationDelay=0.000000E+000
|RECORD=2|OwnerIndex=362|OwnerPartId=2|FormalType=1|PinConglomerate=58|PinLength=30|Location.X=490|Location.Y=778|Name=43|Designator=B-43|PinPropagationDelay=0.000000E+000
|RECORD=2|OwnerIndex=362|OwnerPartId=2|FormalType=1|PinConglomerate=56|PinLength=30|Location.X=550|Location.Y=778|Name=44|Designator=B-44|PinPropagationDelay=0.000000E+000
|RECORD=2|OwnerIndex=362|OwnerPartId=2|FormalType=1|PinConglomerate=58|PinLength=30|Location.X=490|Location.Y=768|Name=45|Designator=B-45|PinPropagationDelay=0.000000E+000
|RECORD=2|OwnerIndex=362|OwnerPartId=2|FormalType=1|PinConglomerate=56|PinLength=30|Location.X=550|Location.Y=768|Name=46|Designator=B-46|PinPropagationDelay=0.000000E+000
|RECORD=2|OwnerIndex=362|OwnerPartId=2|FormalType=1|PinConglomerate=58|PinLength=30|Location.X=490|Location.Y=758|Name=47|Designator=B-47|PinPropagationDelay=0.000000E+000
|RECORD=2|OwnerIndex=362|OwnerPartId=2|FormalType=1|PinConglomerate=56|PinLength=30|Location.X=550|Location.Y=758|Name=48|Designator=B-48|PinPropagationDelay=0.000000E+000
|RECORD=2|OwnerIndex=362|OwnerPartId=2|FormalType=1|PinConglomerate=58|PinLength=30|Location.X=490|Location.Y=748|Name=49|Designator=B-49|PinPropagationDelay=0.000000E+000
|RECORD=2|OwnerIndex=362|OwnerPartId=2|FormalType=1|PinConglomerate=56|PinLength=30|Location.X=550|Location.Y=748|Name=50|Designator=B-50|PinPropagationDelay=0.000000E+000
|RECORD=2|OwnerIndex=362|OwnerPartId=2|FormalType=1|PinConglomerate=58|PinLength=30|Location.X=490|Location.Y=738|Name=51|Designator=B-51|PinPropagationDelay=0.000000E+000
|RECORD=2|OwnerIndex=362|OwnerPartId=2|FormalType=1|PinConglomerate=56|PinLength=30|Location.X=550|Location.Y=738|Name=52|Designator=B-52|PinPropagationDelay=0.000000E+000
|RECORD=2|OwnerIndex=362|OwnerPartId=2|FormalType=1|PinConglomerate=58|PinLength=30|Location.X=490|Location.Y=728|Name=53|Designator=B-53|PinPropagationDelay=0.000000E+000
|RECORD=2|OwnerIndex=362|OwnerPartId=2|FormalType=1|PinConglomerate=56|PinLength=30|Location.X=550|Location.Y=728|Name=54|Designator=B-54|PinPropagationDelay=0.000000E+000
|RECORD=2|OwnerIndex=362|OwnerPartId=2|FormalType=1|PinConglomerate=58|PinLength=30|Location.X=490|Location.Y=718|Name=55|Designator=B-55|PinPropagationDelay=0.000000E+000
|RECORD=2|OwnerIndex=362|OwnerPartId=2|FormalType=1|PinConglomerate=56|PinLength=30|Location.X=550|Location.Y=718|Name=56|Designator=B-56|PinPropagationDelay=0.000000E+000
|RECORD=2|OwnerIndex=362|OwnerPartId=2|FormalType=1|PinConglomerate=58|PinLength=30|Location.X=490|Location.Y=708|Name=57|Designator=B-57|PinPropagationDelay=0.000000E+000
|RECORD=2|OwnerIndex=362|OwnerPartId=2|FormalType=1|PinConglomerate=56|PinLength=30|Location.X=550|Location.Y=708|Name=58|Designator=B-58|PinPropagationDelay=0.000000E+000
|RECORD=2|OwnerIndex=362|OwnerPartId=2|FormalType=1|PinConglomerate=58|PinLength=30|Location.X=490|Location.Y=698|Name=59|Designator=B-59|PinPropagationDelay=0.000000E+000
|RECORD=2|OwnerIndex=362|OwnerPartId=2|FormalType=1|PinConglomerate=56|PinLength=30|Location.X=550|Location.Y=698|Name=60|Designator=B-60|PinPropagationDelay=0.000000E+000
|RECORD=2|OwnerIndex=362|OwnerPartId=2|FormalType=1|PinConglomerate=58|PinLength=30|Location.X=490|Location.Y=688|Name=61|Designator=B-61|PinPropagationDelay=0.000000E+000
|RECORD=2|OwnerIndex=362|OwnerPartId=2|FormalType=1|PinConglomerate=56|PinLength=30|Location.X=550|Location.Y=688|Name=62|Designator=B-62|PinPropagationDelay=0.000000E+000
|RECORD=2|OwnerIndex=362|OwnerPartId=2|FormalType=1|PinConglomerate=58|PinLength=30|Location.X=490|Location.Y=678|Name=63|Designator=B-63|PinPropagationDelay=0.000000E+000
|RECORD=2|OwnerIndex=362|OwnerPartId=2|FormalType=1|PinConglomerate=56|PinLength=30|Location.X=550|Location.Y=678|Name=64|Designator=B-64|PinPropagationDelay=0.000000E+000
|RECORD=2|OwnerIndex=362|OwnerPartId=2|FormalType=1|PinConglomerate=58|PinLength=30|Location.X=490|Location.Y=668|Name=65|Designator=B-65|PinPropagationDelay=0.000000E+000
|RECORD=2|OwnerIndex=362|OwnerPartId=2|FormalType=1|PinConglomerate=56|PinLength=30|Location.X=550|Location.Y=668|Name=66|Designator=B-66|PinPropagationDelay=0.000000E+000
|RECORD=2|OwnerIndex=362|OwnerPartId=2|FormalType=1|PinConglomerate=58|PinLength=30|Location.X=490|Location.Y=658|Name=67|Designator=B-67|PinPropagationDelay=0.000000E+000
|RECORD=2|OwnerIndex=362|OwnerPartId=2|FormalType=1|PinConglomerate=56|PinLength=30|Location.X=550|Location.Y=658|Name=68|Designator=B-68|PinPropagationDelay=0.000000E+000
|RECORD=2|OwnerIndex=362|OwnerPartId=2|FormalType=1|PinConglomerate=58|PinLength=30|Location.X=490|Location.Y=648|Name=69|Designator=B-69|PinPropagationDelay=0.000000E+000
|RECORD=2|OwnerIndex=362|OwnerPartId=2|FormalType=1|PinConglomerate=56|PinLength=30|Location.X=550|Location.Y=648|Name=70|Designator=B-70|PinPropagationDelay=0.000000E+000
|RECORD=2|OwnerIndex=362|OwnerPartId=2|FormalType=1|PinConglomerate=58|PinLength=30|Location.X=490|Location.Y=638|Name=71|Designator=B-71|PinPropagationDelay=0.000000E+000
|RECORD=2|OwnerIndex=362|OwnerPartId=2|FormalType=1|PinConglomerate=56|PinLength=30|Location.X=550|Location.Y=638|Name=72|Designator=B-72|PinPropagationDelay=0.000000E+000
|RECORD=2|OwnerIndex=362|OwnerPartId=2|FormalType=1|PinConglomerate=58|PinLength=30|Location.X=490|Location.Y=628|Name=73|Designator=B-73|PinPropagationDelay=0.000000E+000
|RECORD=2|OwnerIndex=362|OwnerPartId=2|FormalType=1|PinConglomerate=56|PinLength=30|Location.X=550|Location.Y=628|Name=74|Designator=B-74|PinPropagationDelay=0.000000E+000
|RECORD=2|OwnerIndex=362|OwnerPartId=2|FormalType=1|PinConglomerate=58|PinLength=30|Location.X=490|Location.Y=618|Name=75|Designator=B-75|PinPropagationDelay=0.000000E+000
|RECORD=2|OwnerIndex=362|OwnerPartId=2|FormalType=1|PinConglomerate=56|PinLength=30|Location.X=550|Location.Y=618|Name=76|Designator=B-76|PinPropagationDelay=0.000000E+000
|RECORD=2|OwnerIndex=362|OwnerPartId=2|FormalType=1|PinConglomerate=58|PinLength=30|Location.X=490|Location.Y=608|Name=77|Designator=B-77|PinPropagationDelay=0.000000E+000
|RECORD=2|OwnerIndex=362|OwnerPartId=2|FormalType=1|PinConglomerate=56|PinLength=30|Location.X=550|Location.Y=608|Name=78|Designator=B-78|PinPropagationDelay=0.000000E+000
|RECORD=2|OwnerIndex=362|OwnerPartId=2|FormalType=1|PinConglomerate=58|PinLength=30|Location.X=490|Location.Y=598|Name=79|Designator=B-79|PinPropagationDelay=0.000000E+000
|RECORD=2|OwnerIndex=362|OwnerPartId=2|FormalType=1|PinConglomerate=56|PinLength=30|Location.X=550|Location.Y=598|Name=80|Designator=B-80|PinPropagationDelay=0.000000E+000
|RECORD=2|OwnerIndex=362|OwnerPartId=2|FormalType=1|PinConglomerate=58|PinLength=30|Location.X=490|Location.Y=588|Name=81|Designator=B-81|PinPropagationDelay=0.000000E+000
|RECORD=2|OwnerIndex=362|OwnerPartId=2|FormalType=1|PinConglomerate=56|PinLength=30|Location.X=550|Location.Y=588|Name=82|Designator=B-82|PinPropagationDelay=0.000000E+000
|RECORD=2|OwnerIndex=362|OwnerPartId=2|FormalType=1|PinConglomerate=58|PinLength=30|Location.X=490|Location.Y=578|Name=83|Designator=B-83|PinPropagationDelay=0.000000E+000
|RECORD=2|OwnerIndex=362|OwnerPartId=2|FormalType=1|PinConglomerate=56|PinLength=30|Location.X=550|Location.Y=578|Name=84|Designator=B-84|PinPropagationDelay=0.000000E+000
|RECORD=14|OwnerIndex=362|IsNotAccesible=T|IndexInSheet=85|OwnerPartId=3|Location.X=490|Location.Y=568|Corner.X=550|Corner.Y=998|Color=128|AreaColor=11599871|IsSolid=T
|RECORD=2|OwnerIndex=362|OwnerPartId=3|FormalType=1|PinConglomerate=58|PinLength=30|Location.X=490|Location.Y=988|Name=1|Designator=C-1|PinPropagationDelay=0.000000E+000
|RECORD=2|OwnerIndex=362|OwnerPartId=3|FormalType=1|PinConglomerate=56|PinLength=30|Location.X=550|Location.Y=988|Name=2|Designator=C-2|PinPropagationDelay=0.000000E+000
|RECORD=2|OwnerIndex=362|OwnerPartId=3|FormalType=1|PinConglomerate=58|PinLength=30|Location.X=490|Location.Y=978|Name=3|Designator=C-3|PinPropagationDelay=0.000000E+000
|RECORD=2|OwnerIndex=362|OwnerPartId=3|FormalType=1|PinConglomerate=56|PinLength=30|Location.X=550|Location.Y=978|Name=4|Designator=C-4|PinPropagationDelay=0.000000E+000
|RECORD=2|OwnerIndex=362|OwnerPartId=3|FormalType=1|PinConglomerate=58|PinLength=30|Location.X=490|Location.Y=968|Name=5|Designator=C-5|PinPropagationDelay=0.000000E+000
|RECORD=2|OwnerIndex=362|OwnerPartId=3|FormalType=1|PinConglomerate=56|PinLength=30|Location.X=550|Location.Y=968|Name=6|Designator=C-6|PinPropagationDelay=0.000000E+000
|RECORD=2|OwnerIndex=362|OwnerPartId=3|FormalType=1|PinConglomerate=58|PinLength=30|Location.X=490|Location.Y=958|Name=7|Designator=C-7|PinPropagationDelay=0.000000E+000
|RECORD=2|OwnerIndex=362|OwnerPartId=3|FormalType=1|PinConglomerate=56|PinLength=30|Location.X=550|Location.Y=958|Name=8|Designator=C-8|PinPropagationDelay=0.000000E+000
|RECORD=2|OwnerIndex=362|OwnerPartId=3|FormalType=1|PinConglomerate=58|PinLength=30|Location.X=490|Location.Y=948|Name=9|Designator=C-9|PinPropagationDelay=0.000000E+000
|RECORD=2|OwnerIndex=362|OwnerPartId=3|FormalType=1|PinConglomerate=56|PinLength=30|Location.X=550|Location.Y=948|Name=10|Designator=C-10|PinPropagationDelay=0.000000E+000
|RECORD=2|OwnerIndex=362|OwnerPartId=3|FormalType=1|PinConglomerate=58|PinLength=30|Location.X=490|Location.Y=938|Name=11|Designator=C-11|PinPropagationDelay=0.000000E+000
|RECORD=2|OwnerIndex=362|OwnerPartId=3|FormalType=1|PinConglomerate=56|PinLength=30|Location.X=550|Location.Y=938|Name=12|Designator=C-12|PinPropagationDelay=0.000000E+000
|RECORD=2|OwnerIndex=362|OwnerPartId=3|FormalType=1|PinConglomerate=58|PinLength=30|Location.X=490|Location.Y=928|Name=13|Designator=C-13|PinPropagationDelay=0.000000E+000
|RECORD=2|OwnerIndex=362|OwnerPartId=3|FormalType=1|PinConglomerate=56|PinLength=30|Location.X=550|Location.Y=928|Name=14|Designator=C-14|PinPropagationDelay=0.000000E+000
|RECORD=2|OwnerIndex=362|OwnerPartId=3|FormalType=1|PinConglomerate=58|PinLength=30|Location.X=490|Location.Y=918|Name=15|Designator=C-15|PinPropagationDelay=0.000000E+000
|RECORD=2|OwnerIndex=362|OwnerPartId=3|FormalType=1|PinConglomerate=56|PinLength=30|Location.X=550|Location.Y=918|Name=16|Designator=C-16|PinPropagationDelay=0.000000E+000
|RECORD=2|OwnerIndex=362|OwnerPartId=3|FormalType=1|PinConglomerate=58|PinLength=30|Location.X=490|Location.Y=908|Name=17|Designator=C-17|PinPropagationDelay=0.000000E+000
|RECORD=2|OwnerIndex=362|OwnerPartId=3|FormalType=1|PinConglomerate=56|PinLength=30|Location.X=550|Location.Y=908|Name=18|Designator=C-18|PinPropagationDelay=0.000000E+000
|RECORD=2|OwnerIndex=362|OwnerPartId=3|FormalType=1|PinConglomerate=58|PinLength=30|Location.X=490|Location.Y=898|Name=19|Designator=C-19|PinPropagationDelay=0.000000E+000
|RECORD=2|OwnerIndex=362|OwnerPartId=3|FormalType=1|PinConglomerate=56|PinLength=30|Location.X=550|Location.Y=898|Name=20|Designator=C-20|PinPropagationDelay=0.000000E+000
|RECORD=2|OwnerIndex=362|OwnerPartId=3|FormalType=1|PinConglomerate=58|PinLength=30|Location.X=490|Location.Y=888|Name=21|Designator=C-21|PinPropagationDelay=0.000000E+000
|RECORD=2|OwnerIndex=362|OwnerPartId=3|FormalType=1|PinConglomerate=56|PinLength=30|Location.X=550|Location.Y=888|Name=22|Designator=C-22|PinPropagationDelay=0.000000E+000
|RECORD=2|OwnerIndex=362|OwnerPartId=3|FormalType=1|PinConglomerate=58|PinLength=30|Location.X=490|Location.Y=878|Name=23|Designator=C-23|PinPropagationDelay=0.000000E+000
|RECORD=2|OwnerIndex=362|OwnerPartId=3|FormalType=1|PinConglomerate=56|PinLength=30|Location.X=550|Location.Y=878|Name=24|Designator=C-24|PinPropagationDelay=0.000000E+000
|RECORD=2|OwnerIndex=362|OwnerPartId=3|FormalType=1|PinConglomerate=58|PinLength=30|Location.X=490|Location.Y=868|Name=25|Designator=C-25|PinPropagationDelay=0.000000E+000
|RECORD=2|OwnerIndex=362|OwnerPartId=3|FormalType=1|PinConglomerate=56|PinLength=30|Location.X=550|Location.Y=868|Name=26|Designator=C-26|PinPropagationDelay=0.000000E+000
|RECORD=2|OwnerIndex=362|OwnerPartId=3|FormalType=1|PinConglomerate=58|PinLength=30|Location.X=490|Location.Y=858|Name=27|Designator=C-27|PinPropagationDelay=0.000000E+000
|RECORD=2|OwnerIndex=362|OwnerPartId=3|FormalType=1|PinConglomerate=56|PinLength=30|Location.X=550|Location.Y=858|Name=28|Designator=C-28|PinPropagationDelay=0.000000E+000
|RECORD=2|OwnerIndex=362|OwnerPartId=3|FormalType=1|PinConglomerate=58|PinLength=30|Location.X=490|Location.Y=848|Name=29|Designator=C-29|PinPropagationDelay=0.000000E+000
|RECORD=2|OwnerIndex=362|OwnerPartId=3|FormalType=1|PinConglomerate=56|PinLength=30|Location.X=550|Location.Y=848|Name=30|Designator=C-30|PinPropagationDelay=0.000000E+000
|RECORD=2|OwnerIndex=362|OwnerPartId=3|FormalType=1|PinConglomerate=58|PinLength=30|Location.X=490|Location.Y=838|Name=31|Designator=C-31|PinPropagationDelay=0.000000E+000
|RECORD=2|OwnerIndex=362|OwnerPartId=3|FormalType=1|PinConglomerate=56|PinLength=30|Location.X=550|Location.Y=838|Name=32|Designator=C-32|PinPropagationDelay=0.000000E+000
|RECORD=2|OwnerIndex=362|OwnerPartId=3|FormalType=1|PinConglomerate=58|PinLength=30|Location.X=490|Location.Y=828|Name=33|Designator=C-33|PinPropagationDelay=0.000000E+000
|RECORD=2|OwnerIndex=362|OwnerPartId=3|FormalType=1|PinConglomerate=56|PinLength=30|Location.X=550|Location.Y=828|Name=34|Designator=C-34|PinPropagationDelay=0.000000E+000
|RECORD=2|OwnerIndex=362|OwnerPartId=3|FormalType=1|PinConglomerate=58|PinLength=30|Location.X=490|Location.Y=818|Name=35|Designator=C-35|PinPropagationDelay=0.000000E+000
|RECORD=2|OwnerIndex=362|OwnerPartId=3|FormalType=1|PinConglomerate=56|PinLength=30|Location.X=550|Location.Y=818|Name=36|Designator=C-36|PinPropagationDelay=0.000000E+000
|RECORD=2|OwnerIndex=362|OwnerPartId=3|FormalType=1|PinConglomerate=58|PinLength=30|Location.X=490|Location.Y=808|Name=37|Designator=C-37|PinPropagationDelay=0.000000E+000
|RECORD=2|OwnerIndex=362|OwnerPartId=3|FormalType=1|PinConglomerate=56|PinLength=30|Location.X=550|Location.Y=808|Name=38|Designator=C-38|PinPropagationDelay=0.000000E+000
|RECORD=2|OwnerIndex=362|OwnerPartId=3|FormalType=1|PinConglomerate=58|PinLength=30|Location.X=490|Location.Y=798|Name=39|Designator=C-39|PinPropagationDelay=0.000000E+000
|RECORD=2|OwnerIndex=362|OwnerPartId=3|FormalType=1|PinConglomerate=56|PinLength=30|Location.X=550|Location.Y=798|Name=40|Designator=C-40|PinPropagationDelay=0.000000E+000
|RECORD=2|OwnerIndex=362|OwnerPartId=3|FormalType=1|PinConglomerate=58|PinLength=30|Location.X=490|Location.Y=788|Name=41|Designator=C-41|PinPropagationDelay=0.000000E+000
|RECORD=2|OwnerIndex=362|OwnerPartId=3|FormalType=1|PinConglomerate=56|PinLength=30|Location.X=550|Location.Y=788|Name=42|Designator=C-42|PinPropagationDelay=0.000000E+000
|RECORD=2|OwnerIndex=362|OwnerPartId=3|FormalType=1|PinConglomerate=58|PinLength=30|Location.X=490|Location.Y=778|Name=43|Designator=C-43|PinPropagationDelay=0.000000E+000
|RECORD=2|OwnerIndex=362|OwnerPartId=3|FormalType=1|PinConglomerate=56|PinLength=30|Location.X=550|Location.Y=778|Name=44|Designator=C-44|PinPropagationDelay=0.000000E+000
|RECORD=2|OwnerIndex=362|OwnerPartId=3|FormalType=1|PinConglomerate=58|PinLength=30|Location.X=490|Location.Y=768|Name=45|Designator=C-45|PinPropagationDelay=0.000000E+000
|RECORD=2|OwnerIndex=362|OwnerPartId=3|FormalType=1|PinConglomerate=56|PinLength=30|Location.X=550|Location.Y=768|Name=46|Designator=C-46|PinPropagationDelay=0.000000E+000
|RECORD=2|OwnerIndex=362|OwnerPartId=3|FormalType=1|PinConglomerate=58|PinLength=30|Location.X=490|Location.Y=758|Name=47|Designator=C-47|PinPropagationDelay=0.000000E+000
|RECORD=2|OwnerIndex=362|OwnerPartId=3|FormalType=1|PinConglomerate=56|PinLength=30|Location.X=550|Location.Y=758|Name=48|Designator=C-48|PinPropagationDelay=0.000000E+000
|RECORD=2|OwnerIndex=362|OwnerPartId=3|FormalType=1|PinConglomerate=58|PinLength=30|Location.X=490|Location.Y=748|Name=49|Designator=C-49|PinPropagationDelay=0.000000E+000
|RECORD=2|OwnerIndex=362|OwnerPartId=3|FormalType=1|PinConglomerate=56|PinLength=30|Location.X=550|Location.Y=748|Name=50|Designator=C-50|PinPropagationDelay=0.000000E+000
|RECORD=2|OwnerIndex=362|OwnerPartId=3|FormalType=1|PinConglomerate=58|PinLength=30|Location.X=490|Location.Y=738|Name=51|Designator=C-51|PinPropagationDelay=0.000000E+000
|RECORD=2|OwnerIndex=362|OwnerPartId=3|FormalType=1|PinConglomerate=56|PinLength=30|Location.X=550|Location.Y=738|Name=52|Designator=C-52|PinPropagationDelay=0.000000E+000
|RECORD=2|OwnerIndex=362|OwnerPartId=3|FormalType=1|PinConglomerate=58|PinLength=30|Location.X=490|Location.Y=728|Name=53|Designator=C-53|PinPropagationDelay=0.000000E+000
|RECORD=2|OwnerIndex=362|OwnerPartId=3|FormalType=1|PinConglomerate=56|PinLength=30|Location.X=550|Location.Y=728|Name=54|Designator=C-54|PinPropagationDelay=0.000000E+000
|RECORD=2|OwnerIndex=362|OwnerPartId=3|FormalType=1|PinConglomerate=58|PinLength=30|Location.X=490|Location.Y=718|Name=55|Designator=C-55|PinPropagationDelay=0.000000E+000
|RECORD=2|OwnerIndex=362|OwnerPartId=3|FormalType=1|PinConglomerate=56|PinLength=30|Location.X=550|Location.Y=718|Name=56|Designator=C-56|PinPropagationDelay=0.000000E+000
|RECORD=2|OwnerIndex=362|OwnerPartId=3|FormalType=1|PinConglomerate=58|PinLength=30|Location.X=490|Location.Y=708|Name=57|Designator=C-57|PinPropagationDelay=0.000000E+000
|RECORD=2|OwnerIndex=362|OwnerPartId=3|FormalType=1|PinConglomerate=56|PinLength=30|Location.X=550|Location.Y=708|Name=58|Designator=C-58|PinPropagationDelay=0.000000E+000
|RECORD=2|OwnerIndex=362|OwnerPartId=3|FormalType=1|PinConglomerate=58|PinLength=30|Location.X=490|Location.Y=698|Name=59|Designator=C-59|PinPropagationDelay=0.000000E+000
|RECORD=2|OwnerIndex=362|OwnerPartId=3|FormalType=1|PinConglomerate=56|PinLength=30|Location.X=550|Location.Y=698|Name=60|Designator=C-60|PinPropagationDelay=0.000000E+000
|RECORD=2|OwnerIndex=362|OwnerPartId=3|FormalType=1|PinConglomerate=58|PinLength=30|Location.X=490|Location.Y=688|Name=61|Designator=C-61|PinPropagationDelay=0.000000E+000
|RECORD=2|OwnerIndex=362|OwnerPartId=3|FormalType=1|PinConglomerate=56|PinLength=30|Location.X=550|Location.Y=688|Name=62|Designator=C-62|PinPropagationDelay=0.000000E+000
|RECORD=2|OwnerIndex=362|OwnerPartId=3|FormalType=1|PinConglomerate=58|PinLength=30|Location.X=490|Location.Y=678|Name=63|Designator=C-63|PinPropagationDelay=0.000000E+000
|RECORD=2|OwnerIndex=362|OwnerPartId=3|FormalType=1|PinConglomerate=56|PinLength=30|Location.X=550|Location.Y=678|Name=64|Designator=C-64|PinPropagationDelay=0.000000E+000
|RECORD=2|OwnerIndex=362|OwnerPartId=3|FormalType=1|PinConglomerate=58|PinLength=30|Location.X=490|Location.Y=668|Name=65|Designator=C-65|PinPropagationDelay=0.000000E+000
|RECORD=2|OwnerIndex=362|OwnerPartId=3|FormalType=1|PinConglomerate=56|PinLength=30|Location.X=550|Location.Y=668|Name=66|Designator=C-66|PinPropagationDelay=0.000000E+000
|RECORD=2|OwnerIndex=362|OwnerPartId=3|FormalType=1|PinConglomerate=58|PinLength=30|Location.X=490|Location.Y=658|Name=67|Designator=C-67|PinPropagationDelay=0.000000E+000
|RECORD=2|OwnerIndex=362|OwnerPartId=3|FormalType=1|PinConglomerate=56|PinLength=30|Location.X=550|Location.Y=658|Name=68|Designator=C-68|PinPropagationDelay=0.000000E+000
|RECORD=2|OwnerIndex=362|OwnerPartId=3|FormalType=1|PinConglomerate=58|PinLength=30|Location.X=490|Location.Y=648|Name=69|Designator=C-69|PinPropagationDelay=0.000000E+000
|RECORD=2|OwnerIndex=362|OwnerPartId=3|FormalType=1|PinConglomerate=56|PinLength=30|Location.X=550|Location.Y=648|Name=70|Designator=C-70|PinPropagationDelay=0.000000E+000
|RECORD=2|OwnerIndex=362|OwnerPartId=3|FormalType=1|PinConglomerate=58|PinLength=30|Location.X=490|Location.Y=638|Name=71|Designator=C-71|PinPropagationDelay=0.000000E+000
|RECORD=2|OwnerIndex=362|OwnerPartId=3|FormalType=1|PinConglomerate=56|PinLength=30|Location.X=550|Location.Y=638|Name=72|Designator=C-72|PinPropagationDelay=0.000000E+000
|RECORD=2|OwnerIndex=362|OwnerPartId=3|FormalType=1|PinConglomerate=58|PinLength=30|Location.X=490|Location.Y=628|Name=73|Designator=C-73|PinPropagationDelay=0.000000E+000
|RECORD=2|OwnerIndex=362|OwnerPartId=3|FormalType=1|PinConglomerate=56|PinLength=30|Location.X=550|Location.Y=628|Name=74|Designator=C-74|PinPropagationDelay=0.000000E+000
|RECORD=2|OwnerIndex=362|OwnerPartId=3|FormalType=1|PinConglomerate=58|PinLength=30|Location.X=490|Location.Y=618|Name=75|Designator=C-75|PinPropagationDelay=0.000000E+000
|RECORD=2|OwnerIndex=362|OwnerPartId=3|FormalType=1|PinConglomerate=56|PinLength=30|Location.X=550|Location.Y=618|Name=76|Designator=C-76|PinPropagationDelay=0.000000E+000
|RECORD=2|OwnerIndex=362|OwnerPartId=3|FormalType=1|PinConglomerate=58|PinLength=30|Location.X=490|Location.Y=608|Name=77|Designator=C-77|PinPropagationDelay=0.000000E+000
|RECORD=2|OwnerIndex=362|OwnerPartId=3|FormalType=1|PinConglomerate=56|PinLength=30|Location.X=550|Location.Y=608|Name=78|Designator=C-78|PinPropagationDelay=0.000000E+000
|RECORD=2|OwnerIndex=362|OwnerPartId=3|FormalType=1|PinConglomerate=58|PinLength=30|Location.X=490|Location.Y=598|Name=79|Designator=C-79|PinPropagationDelay=0.000000E+000
|RECORD=2|OwnerIndex=362|OwnerPartId=3|FormalType=1|PinConglomerate=56|PinLength=30|Location.X=550|Location.Y=598|Name=80|Designator=C-80|PinPropagationDelay=0.000000E+000
|RECORD=2|OwnerIndex=362|OwnerPartId=3|FormalType=1|PinConglomerate=58|PinLength=30|Location.X=490|Location.Y=588|Name=81|Designator=C-81|PinPropagationDelay=0.000000E+000
|RECORD=2|OwnerIndex=362|OwnerPartId=3|FormalType=1|PinConglomerate=56|PinLength=30|Location.X=550|Location.Y=588|Name=82|Designator=C-82|PinPropagationDelay=0.000000E+000
|RECORD=2|OwnerIndex=362|OwnerPartId=3|FormalType=1|PinConglomerate=58|PinLength=30|Location.X=490|Location.Y=578|Name=83|Designator=C-83|PinPropagationDelay=0.000000E+000
|RECORD=2|OwnerIndex=362|OwnerPartId=3|FormalType=1|PinConglomerate=56|PinLength=30|Location.X=550|Location.Y=578|Name=84|Designator=C-84|PinPropagationDelay=0.000000E+000
|RECORD=14|OwnerIndex=362|IsNotAccesible=T|IndexInSheet=170|OwnerPartId=4|Location.X=490|Location.Y=568|Corner.X=550|Corner.Y=998|Color=128|AreaColor=11599871|IsSolid=T
|RECORD=2|OwnerIndex=362|OwnerPartId=4|FormalType=1|PinConglomerate=58|PinLength=30|Location.X=490|Location.Y=988|Name=1|Designator=D-1|PinPropagationDelay=0.000000E+000
|RECORD=2|OwnerIndex=362|OwnerPartId=4|FormalType=1|PinConglomerate=56|PinLength=30|Location.X=550|Location.Y=988|Name=2|Designator=D-2|PinPropagationDelay=0.000000E+000
|RECORD=2|OwnerIndex=362|OwnerPartId=4|FormalType=1|PinConglomerate=58|PinLength=30|Location.X=490|Location.Y=978|Name=3|Designator=D-3|PinPropagationDelay=0.000000E+000
|RECORD=2|OwnerIndex=362|OwnerPartId=4|FormalType=1|PinConglomerate=56|PinLength=30|Location.X=550|Location.Y=978|Name=4|Designator=D-4|PinPropagationDelay=0.000000E+000
|RECORD=2|OwnerIndex=362|OwnerPartId=4|FormalType=1|PinConglomerate=58|PinLength=30|Location.X=490|Location.Y=968|Name=5|Designator=D-5|PinPropagationDelay=0.000000E+000
|RECORD=2|OwnerIndex=362|OwnerPartId=4|FormalType=1|PinConglomerate=56|PinLength=30|Location.X=550|Location.Y=968|Name=6|Designator=D-6|PinPropagationDelay=0.000000E+000
|RECORD=2|OwnerIndex=362|OwnerPartId=4|FormalType=1|PinConglomerate=58|PinLength=30|Location.X=490|Location.Y=958|Name=7|Designator=D-7|PinPropagationDelay=0.000000E+000
|RECORD=2|OwnerIndex=362|OwnerPartId=4|FormalType=1|PinConglomerate=56|PinLength=30|Location.X=550|Location.Y=958|Name=8|Designator=D-8|PinPropagationDelay=0.000000E+000
|RECORD=2|OwnerIndex=362|OwnerPartId=4|FormalType=1|PinConglomerate=58|PinLength=30|Location.X=490|Location.Y=948|Name=9|Designator=D-9|PinPropagationDelay=0.000000E+000
|RECORD=2|OwnerIndex=362|OwnerPartId=4|FormalType=1|PinConglomerate=56|PinLength=30|Location.X=550|Location.Y=948|Name=10|Designator=D-10|PinPropagationDelay=0.000000E+000
|RECORD=2|OwnerIndex=362|OwnerPartId=4|FormalType=1|PinConglomerate=58|PinLength=30|Location.X=490|Location.Y=938|Name=11|Designator=D-11|PinPropagationDelay=0.000000E+000
|RECORD=2|OwnerIndex=362|OwnerPartId=4|FormalType=1|PinConglomerate=56|PinLength=30|Location.X=550|Location.Y=938|Name=12|Designator=D-12|PinPropagationDelay=0.000000E+000
|RECORD=2|OwnerIndex=362|OwnerPartId=4|FormalType=1|PinConglomerate=58|PinLength=30|Location.X=490|Location.Y=928|Name=13|Designator=D-13|PinPropagationDelay=0.000000E+000
|RECORD=2|OwnerIndex=362|OwnerPartId=4|FormalType=1|PinConglomerate=56|PinLength=30|Location.X=550|Location.Y=928|Name=14|Designator=D-14|PinPropagationDelay=0.000000E+000
|RECORD=2|OwnerIndex=362|OwnerPartId=4|FormalType=1|PinConglomerate=58|PinLength=30|Location.X=490|Location.Y=918|Name=15|Designator=D-15|PinPropagationDelay=0.000000E+000
|RECORD=2|OwnerIndex=362|OwnerPartId=4|FormalType=1|PinConglomerate=56|PinLength=30|Location.X=550|Location.Y=918|Name=16|Designator=D-16|PinPropagationDelay=0.000000E+000
|RECORD=2|OwnerIndex=362|OwnerPartId=4|FormalType=1|PinConglomerate=58|PinLength=30|Location.X=490|Location.Y=908|Name=17|Designator=D-17|PinPropagationDelay=0.000000E+000
|RECORD=2|OwnerIndex=362|OwnerPartId=4|FormalType=1|PinConglomerate=56|PinLength=30|Location.X=550|Location.Y=908|Name=18|Designator=D-18|PinPropagationDelay=0.000000E+000
|RECORD=2|OwnerIndex=362|OwnerPartId=4|FormalType=1|PinConglomerate=58|PinLength=30|Location.X=490|Location.Y=898|Name=19|Designator=D-19|PinPropagationDelay=0.000000E+000
|RECORD=2|OwnerIndex=362|OwnerPartId=4|FormalType=1|PinConglomerate=56|PinLength=30|Location.X=550|Location.Y=898|Name=20|Designator=D-20|PinPropagationDelay=0.000000E+000
|RECORD=2|OwnerIndex=362|OwnerPartId=4|FormalType=1|PinConglomerate=58|PinLength=30|Location.X=490|Location.Y=888|Name=21|Designator=D-21|PinPropagationDelay=0.000000E+000
|RECORD=2|OwnerIndex=362|OwnerPartId=4|FormalType=1|PinConglomerate=56|PinLength=30|Location.X=550|Location.Y=888|Name=22|Designator=D-22|PinPropagationDelay=0.000000E+000
|RECORD=2|OwnerIndex=362|OwnerPartId=4|FormalType=1|PinConglomerate=58|PinLength=30|Location.X=490|Location.Y=878|Name=23|Designator=D-23|PinPropagationDelay=0.000000E+000
|RECORD=2|OwnerIndex=362|OwnerPartId=4|FormalType=1|PinConglomerate=56|PinLength=30|Location.X=550|Location.Y=878|Name=24|Designator=D-24|PinPropagationDelay=0.000000E+000
|RECORD=2|OwnerIndex=362|OwnerPartId=4|FormalType=1|PinConglomerate=58|PinLength=30|Location.X=490|Location.Y=868|Name=25|Designator=D-25|PinPropagationDelay=0.000000E+000
|RECORD=2|OwnerIndex=362|OwnerPartId=4|FormalType=1|PinConglomerate=56|PinLength=30|Location.X=550|Location.Y=868|Name=26|Designator=D-26|PinPropagationDelay=0.000000E+000
|RECORD=2|OwnerIndex=362|OwnerPartId=4|FormalType=1|PinConglomerate=58|PinLength=30|Location.X=490|Location.Y=858|Name=27|Designator=D-27|PinPropagationDelay=0.000000E+000
|RECORD=2|OwnerIndex=362|OwnerPartId=4|FormalType=1|PinConglomerate=56|PinLength=30|Location.X=550|Location.Y=858|Name=28|Designator=D-28|PinPropagationDelay=0.000000E+000
|RECORD=2|OwnerIndex=362|OwnerPartId=4|FormalType=1|PinConglomerate=58|PinLength=30|Location.X=490|Location.Y=848|Name=29|Designator=D-29|PinPropagationDelay=0.000000E+000
|RECORD=2|OwnerIndex=362|OwnerPartId=4|FormalType=1|PinConglomerate=56|PinLength=30|Location.X=550|Location.Y=848|Name=30|Designator=D-30|PinPropagationDelay=0.000000E+000
|RECORD=2|OwnerIndex=362|OwnerPartId=4|FormalType=1|PinConglomerate=58|PinLength=30|Location.X=490|Location.Y=838|Name=31|Designator=D-31|PinPropagationDelay=0.000000E+000
|RECORD=2|OwnerIndex=362|OwnerPartId=4|FormalType=1|PinConglomerate=56|PinLength=30|Location.X=550|Location.Y=838|Name=32|Designator=D-32|PinPropagationDelay=0.000000E+000
|RECORD=2|OwnerIndex=362|OwnerPartId=4|FormalType=1|PinConglomerate=58|PinLength=30|Location.X=490|Location.Y=828|Name=33|Designator=D-33|PinPropagationDelay=0.000000E+000
|RECORD=2|OwnerIndex=362|OwnerPartId=4|FormalType=1|PinConglomerate=56|PinLength=30|Location.X=550|Location.Y=828|Name=34|Designator=D-34|PinPropagationDelay=0.000000E+000
|RECORD=2|OwnerIndex=362|OwnerPartId=4|FormalType=1|PinConglomerate=58|PinLength=30|Location.X=490|Location.Y=818|Name=35|Designator=D-35|PinPropagationDelay=0.000000E+000
|RECORD=2|OwnerIndex=362|OwnerPartId=4|FormalType=1|PinConglomerate=56|PinLength=30|Location.X=550|Location.Y=818|Name=36|Designator=D-36|PinPropagationDelay=0.000000E+000
|RECORD=2|OwnerIndex=362|OwnerPartId=4|FormalType=1|PinConglomerate=58|PinLength=30|Location.X=490|Location.Y=808|Name=37|Designator=D-37|PinPropagationDelay=0.000000E+000
|RECORD=2|OwnerIndex=362|OwnerPartId=4|FormalType=1|PinConglomerate=56|PinLength=30|Location.X=550|Location.Y=808|Name=38|Designator=D-38|PinPropagationDelay=0.000000E+000
|RECORD=2|OwnerIndex=362|OwnerPartId=4|FormalType=1|PinConglomerate=58|PinLength=30|Location.X=490|Location.Y=798|Name=39|Designator=D-39|PinPropagationDelay=0.000000E+000
|RECORD=2|OwnerIndex=362|OwnerPartId=4|FormalType=1|PinConglomerate=56|PinLength=30|Location.X=550|Location.Y=798|Name=40|Designator=D-40|PinPropagationDelay=0.000000E+000
|RECORD=2|OwnerIndex=362|OwnerPartId=4|FormalType=1|PinConglomerate=58|PinLength=30|Location.X=490|Location.Y=788|Name=41|Designator=D-41|PinPropagationDelay=0.000000E+000
|RECORD=2|OwnerIndex=362|OwnerPartId=4|FormalType=1|PinConglomerate=56|PinLength=30|Location.X=550|Location.Y=788|Name=42|Designator=D-42|PinPropagationDelay=0.000000E+000
|RECORD=2|OwnerIndex=362|OwnerPartId=4|FormalType=1|PinConglomerate=58|PinLength=30|Location.X=490|Location.Y=778|Name=43|Designator=D-43|PinPropagationDelay=0.000000E+000
|RECORD=2|OwnerIndex=362|OwnerPartId=4|FormalType=1|PinConglomerate=56|PinLength=30|Location.X=550|Location.Y=778|Name=44|Designator=D-44|PinPropagationDelay=0.000000E+000
|RECORD=2|OwnerIndex=362|OwnerPartId=4|FormalType=1|PinConglomerate=58|PinLength=30|Location.X=490|Location.Y=768|Name=45|Designator=D-45|PinPropagationDelay=0.000000E+000
|RECORD=2|OwnerIndex=362|OwnerPartId=4|FormalType=1|PinConglomerate=56|PinLength=30|Location.X=550|Location.Y=768|Name=46|Designator=D-46|PinPropagationDelay=0.000000E+000
|RECORD=2|OwnerIndex=362|OwnerPartId=4|FormalType=1|PinConglomerate=58|PinLength=30|Location.X=490|Location.Y=758|Name=47|Designator=D-47|PinPropagationDelay=0.000000E+000
|RECORD=2|OwnerIndex=362|OwnerPartId=4|FormalType=1|PinConglomerate=56|PinLength=30|Location.X=550|Location.Y=758|Name=48|Designator=D-48|PinPropagationDelay=0.000000E+000
|RECORD=2|OwnerIndex=362|OwnerPartId=4|FormalType=1|PinConglomerate=58|PinLength=30|Location.X=490|Location.Y=748|Name=49|Designator=D-49|PinPropagationDelay=0.000000E+000
|RECORD=2|OwnerIndex=362|OwnerPartId=4|FormalType=1|PinConglomerate=56|PinLength=30|Location.X=550|Location.Y=748|Name=50|Designator=D-50|PinPropagationDelay=0.000000E+000
|RECORD=2|OwnerIndex=362|OwnerPartId=4|FormalType=1|PinConglomerate=58|PinLength=30|Location.X=490|Location.Y=738|Name=51|Designator=D-51|PinPropagationDelay=0.000000E+000
|RECORD=2|OwnerIndex=362|OwnerPartId=4|FormalType=1|PinConglomerate=56|PinLength=30|Location.X=550|Location.Y=738|Name=52|Designator=D-52|PinPropagationDelay=0.000000E+000
|RECORD=2|OwnerIndex=362|OwnerPartId=4|FormalType=1|PinConglomerate=58|PinLength=30|Location.X=490|Location.Y=728|Name=53|Designator=D-53|PinPropagationDelay=0.000000E+000
|RECORD=2|OwnerIndex=362|OwnerPartId=4|FormalType=1|PinConglomerate=56|PinLength=30|Location.X=550|Location.Y=728|Name=54|Designator=D-54|PinPropagationDelay=0.000000E+000
|RECORD=2|OwnerIndex=362|OwnerPartId=4|FormalType=1|PinConglomerate=58|PinLength=30|Location.X=490|Location.Y=718|Name=55|Designator=D-55|PinPropagationDelay=0.000000E+000
|RECORD=2|OwnerIndex=362|OwnerPartId=4|FormalType=1|PinConglomerate=56|PinLength=30|Location.X=550|Location.Y=718|Name=56|Designator=D-56|PinPropagationDelay=0.000000E+000
|RECORD=2|OwnerIndex=362|OwnerPartId=4|FormalType=1|PinConglomerate=58|PinLength=30|Location.X=490|Location.Y=708|Name=57|Designator=D-57|PinPropagationDelay=0.000000E+000
|RECORD=2|OwnerIndex=362|OwnerPartId=4|FormalType=1|PinConglomerate=56|PinLength=30|Location.X=550|Location.Y=708|Name=58|Designator=D-58|PinPropagationDelay=0.000000E+000
|RECORD=2|OwnerIndex=362|OwnerPartId=4|FormalType=1|PinConglomerate=58|PinLength=30|Location.X=490|Location.Y=698|Name=59|Designator=D-59|PinPropagationDelay=0.000000E+000
|RECORD=2|OwnerIndex=362|OwnerPartId=4|FormalType=1|PinConglomerate=56|PinLength=30|Location.X=550|Location.Y=698|Name=60|Designator=D-60|PinPropagationDelay=0.000000E+000
|RECORD=2|OwnerIndex=362|OwnerPartId=4|FormalType=1|PinConglomerate=58|PinLength=30|Location.X=490|Location.Y=688|Name=61|Designator=D-61|PinPropagationDelay=0.000000E+000
|RECORD=2|OwnerIndex=362|OwnerPartId=4|FormalType=1|PinConglomerate=56|PinLength=30|Location.X=550|Location.Y=688|Name=62|Designator=D-62|PinPropagationDelay=0.000000E+000
|RECORD=2|OwnerIndex=362|OwnerPartId=4|FormalType=1|PinConglomerate=58|PinLength=30|Location.X=490|Location.Y=678|Name=63|Designator=D-63|PinPropagationDelay=0.000000E+000
|RECORD=2|OwnerIndex=362|OwnerPartId=4|FormalType=1|PinConglomerate=56|PinLength=30|Location.X=550|Location.Y=678|Name=64|Designator=D-64|PinPropagationDelay=0.000000E+000
|RECORD=2|OwnerIndex=362|OwnerPartId=4|FormalType=1|PinConglomerate=58|PinLength=30|Location.X=490|Location.Y=668|Name=65|Designator=D-65|PinPropagationDelay=0.000000E+000
|RECORD=2|OwnerIndex=362|OwnerPartId=4|FormalType=1|PinConglomerate=56|PinLength=30|Location.X=550|Location.Y=668|Name=66|Designator=D-66|PinPropagationDelay=0.000000E+000
|RECORD=2|OwnerIndex=362|OwnerPartId=4|FormalType=1|PinConglomerate=58|PinLength=30|Location.X=490|Location.Y=658|Name=67|Designator=D-67|PinPropagationDelay=0.000000E+000
|RECORD=2|OwnerIndex=362|OwnerPartId=4|FormalType=1|PinConglomerate=56|PinLength=30|Location.X=550|Location.Y=658|Name=68|Designator=D-68|PinPropagationDelay=0.000000E+000
|RECORD=2|OwnerIndex=362|OwnerPartId=4|FormalType=1|PinConglomerate=58|PinLength=30|Location.X=490|Location.Y=648|Name=69|Designator=D-69|PinPropagationDelay=0.000000E+000
|RECORD=2|OwnerIndex=362|OwnerPartId=4|FormalType=1|PinConglomerate=56|PinLength=30|Location.X=550|Location.Y=648|Name=70|Designator=D-70|PinPropagationDelay=0.000000E+000
|RECORD=2|OwnerIndex=362|OwnerPartId=4|FormalType=1|PinConglomerate=58|PinLength=30|Location.X=490|Location.Y=638|Name=71|Designator=D-71|PinPropagationDelay=0.000000E+000
|RECORD=2|OwnerIndex=362|OwnerPartId=4|FormalType=1|PinConglomerate=56|PinLength=30|Location.X=550|Location.Y=638|Name=72|Designator=D-72|PinPropagationDelay=0.000000E+000
|RECORD=2|OwnerIndex=362|OwnerPartId=4|FormalType=1|PinConglomerate=58|PinLength=30|Location.X=490|Location.Y=628|Name=73|Designator=D-73|PinPropagationDelay=0.000000E+000
|RECORD=2|OwnerIndex=362|OwnerPartId=4|FormalType=1|PinConglomerate=56|PinLength=30|Location.X=550|Location.Y=628|Name=74|Designator=D-74|PinPropagationDelay=0.000000E+000
|RECORD=2|OwnerIndex=362|OwnerPartId=4|FormalType=1|PinConglomerate=58|PinLength=30|Location.X=490|Location.Y=618|Name=75|Designator=D-75|PinPropagationDelay=0.000000E+000
|RECORD=2|OwnerIndex=362|OwnerPartId=4|FormalType=1|PinConglomerate=56|PinLength=30|Location.X=550|Location.Y=618|Name=76|Designator=D-76|PinPropagationDelay=0.000000E+000
|RECORD=2|OwnerIndex=362|OwnerPartId=4|FormalType=1|PinConglomerate=58|PinLength=30|Location.X=490|Location.Y=608|Name=77|Designator=D-77|PinPropagationDelay=0.000000E+000
|RECORD=2|OwnerIndex=362|OwnerPartId=4|FormalType=1|PinConglomerate=56|PinLength=30|Location.X=550|Location.Y=608|Name=78|Designator=D-78|PinPropagationDelay=0.000000E+000
|RECORD=2|OwnerIndex=362|OwnerPartId=4|FormalType=1|PinConglomerate=58|PinLength=30|Location.X=490|Location.Y=598|Name=79|Designator=D-79|PinPropagationDelay=0.000000E+000
|RECORD=2|OwnerIndex=362|OwnerPartId=4|FormalType=1|PinConglomerate=56|PinLength=30|Location.X=550|Location.Y=598|Name=80|Designator=D-80|PinPropagationDelay=0.000000E+000
|RECORD=2|OwnerIndex=362|OwnerPartId=4|FormalType=1|PinConglomerate=58|PinLength=30|Location.X=490|Location.Y=588|Name=81|Designator=D-81|PinPropagationDelay=0.000000E+000
|RECORD=2|OwnerIndex=362|OwnerPartId=4|FormalType=1|PinConglomerate=56|PinLength=30|Location.X=550|Location.Y=588|Name=82|Designator=D-82|PinPropagationDelay=0.000000E+000
|RECORD=2|OwnerIndex=362|OwnerPartId=4|FormalType=1|PinConglomerate=58|PinLength=30|Location.X=490|Location.Y=578|Name=83|Designator=D-83|PinPropagationDelay=0.000000E+000
|RECORD=2|OwnerIndex=362|OwnerPartId=4|FormalType=1|PinConglomerate=56|PinLength=30|Location.X=550|Location.Y=578|Name=84|Designator=D-84|PinPropagationDelay=0.000000E+000
|RECORD=14|OwnerIndex=362|IsNotAccesible=T|IndexInSheet=255|OwnerPartId=1|Location.X=490|Location.Y=568|Corner.X=550|Corner.Y=998|Color=128|AreaColor=11599871|IsSolid=T
|RECORD=2|OwnerIndex=362|OwnerPartId=1|FormalType=1|PinConglomerate=58|PinLength=30|Location.X=490|Location.Y=988|Name=1|Designator=A-1|PinPropagationDelay=0.000000E+000
|RECORD=2|OwnerIndex=362|OwnerPartId=1|FormalType=1|PinConglomerate=56|PinLength=30|Location.X=550|Location.Y=988|Name=2|Designator=A-2|PinPropagationDelay=0.000000E+000
|RECORD=2|OwnerIndex=362|OwnerPartId=1|FormalType=1|PinConglomerate=58|PinLength=30|Location.X=490|Location.Y=978|Name=3|Designator=A-3|PinPropagationDelay=0.000000E+000
|RECORD=2|OwnerIndex=362|OwnerPartId=1|FormalType=1|PinConglomerate=56|PinLength=30|Location.X=550|Location.Y=978|Name=4|Designator=A-4|PinPropagationDelay=0.000000E+000
|RECORD=2|OwnerIndex=362|OwnerPartId=1|FormalType=1|PinConglomerate=58|PinLength=30|Location.X=490|Location.Y=968|Name=5|Designator=A-5|PinPropagationDelay=0.000000E+000
|RECORD=2|OwnerIndex=362|OwnerPartId=1|FormalType=1|PinConglomerate=56|PinLength=30|Location.X=550|Location.Y=968|Name=6|Designator=A-6|PinPropagationDelay=0.000000E+000
|RECORD=2|OwnerIndex=362|OwnerPartId=1|FormalType=1|PinConglomerate=58|PinLength=30|Location.X=490|Location.Y=958|Name=7|Designator=A-7|PinPropagationDelay=0.000000E+000
|RECORD=2|OwnerIndex=362|OwnerPartId=1|FormalType=1|PinConglomerate=56|PinLength=30|Location.X=550|Location.Y=958|Name=8|Designator=A-8|PinPropagationDelay=0.000000E+000
|RECORD=2|OwnerIndex=362|OwnerPartId=1|FormalType=1|PinConglomerate=58|PinLength=30|Location.X=490|Location.Y=948|Name=9|Designator=A-9|PinPropagationDelay=0.000000E+000
|RECORD=2|OwnerIndex=362|OwnerPartId=1|FormalType=1|PinConglomerate=56|PinLength=30|Location.X=550|Location.Y=948|Name=10|Designator=A-10|PinPropagationDelay=0.000000E+000
|RECORD=2|OwnerIndex=362|OwnerPartId=1|FormalType=1|PinConglomerate=58|PinLength=30|Location.X=490|Location.Y=938|Name=11|Designator=A-11|PinPropagationDelay=0.000000E+000
|RECORD=2|OwnerIndex=362|OwnerPartId=1|FormalType=1|PinConglomerate=56|PinLength=30|Location.X=550|Location.Y=938|Name=12|Designator=A-12|PinPropagationDelay=0.000000E+000
|RECORD=2|OwnerIndex=362|OwnerPartId=1|FormalType=1|PinConglomerate=58|PinLength=30|Location.X=490|Location.Y=928|Name=13|Designator=A-13|PinPropagationDelay=0.000000E+000
|RECORD=2|OwnerIndex=362|OwnerPartId=1|FormalType=1|PinConglomerate=56|PinLength=30|Location.X=550|Location.Y=928|Name=14|Designator=A-14|PinPropagationDelay=0.000000E+000
|RECORD=2|OwnerIndex=362|OwnerPartId=1|FormalType=1|PinConglomerate=58|PinLength=30|Location.X=490|Location.Y=918|Name=15|Designator=A-15|PinPropagationDelay=0.000000E+000
|RECORD=2|OwnerIndex=362|OwnerPartId=1|FormalType=1|PinConglomerate=56|PinLength=30|Location.X=550|Location.Y=918|Name=16|Designator=A-16|PinPropagationDelay=0.000000E+000
|RECORD=2|OwnerIndex=362|OwnerPartId=1|FormalType=1|PinConglomerate=58|PinLength=30|Location.X=490|Location.Y=908|Name=17|Designator=A-17|PinPropagationDelay=0.000000E+000
|RECORD=2|OwnerIndex=362|OwnerPartId=1|FormalType=1|PinConglomerate=56|PinLength=30|Location.X=550|Location.Y=908|Name=18|Designator=A-18|PinPropagationDelay=0.000000E+000
|RECORD=2|OwnerIndex=362|OwnerPartId=1|FormalType=1|PinConglomerate=58|PinLength=30|Location.X=490|Location.Y=898|Name=19|Designator=A-19|PinPropagationDelay=0.000000E+000
|RECORD=2|OwnerIndex=362|OwnerPartId=1|FormalType=1|PinConglomerate=56|PinLength=30|Location.X=550|Location.Y=898|Name=20|Designator=A-20|PinPropagationDelay=0.000000E+000
|RECORD=2|OwnerIndex=362|OwnerPartId=1|FormalType=1|PinConglomerate=58|PinLength=30|Location.X=490|Location.Y=888|Name=21|Designator=A-21|PinPropagationDelay=0.000000E+000
|RECORD=2|OwnerIndex=362|OwnerPartId=1|FormalType=1|PinConglomerate=56|PinLength=30|Location.X=550|Location.Y=888|Name=22|Designator=A-22|PinPropagationDelay=0.000000E+000
|RECORD=2|OwnerIndex=362|OwnerPartId=1|FormalType=1|PinConglomerate=58|PinLength=30|Location.X=490|Location.Y=878|Name=23|Designator=A-23|PinPropagationDelay=0.000000E+000
|RECORD=2|OwnerIndex=362|OwnerPartId=1|FormalType=1|PinConglomerate=56|PinLength=30|Location.X=550|Location.Y=878|Name=24|Designator=A-24|PinPropagationDelay=0.000000E+000
|RECORD=2|OwnerIndex=362|OwnerPartId=1|FormalType=1|PinConglomerate=58|PinLength=30|Location.X=490|Location.Y=868|Name=25|Designator=A-25|PinPropagationDelay=0.000000E+000
|RECORD=2|OwnerIndex=362|OwnerPartId=1|FormalType=1|PinConglomerate=56|PinLength=30|Location.X=550|Location.Y=868|Name=26|Designator=A-26|PinPropagationDelay=0.000000E+000
|RECORD=2|OwnerIndex=362|OwnerPartId=1|FormalType=1|PinConglomerate=58|PinLength=30|Location.X=490|Location.Y=858|Name=27|Designator=A-27|PinPropagationDelay=0.000000E+000
|RECORD=2|OwnerIndex=362|OwnerPartId=1|FormalType=1|PinConglomerate=56|PinLength=30|Location.X=550|Location.Y=858|Name=28|Designator=A-28|PinPropagationDelay=0.000000E+000
|RECORD=2|OwnerIndex=362|OwnerPartId=1|FormalType=1|PinConglomerate=58|PinLength=30|Location.X=490|Location.Y=848|Name=29|Designator=A-29|PinPropagationDelay=0.000000E+000
|RECORD=2|OwnerIndex=362|OwnerPartId=1|FormalType=1|PinConglomerate=56|PinLength=30|Location.X=550|Location.Y=848|Name=30|Designator=A-30|PinPropagationDelay=0.000000E+000
|RECORD=2|OwnerIndex=362|OwnerPartId=1|FormalType=1|PinConglomerate=58|PinLength=30|Location.X=490|Location.Y=838|Name=31|Designator=A-31|PinPropagationDelay=0.000000E+000
|RECORD=2|OwnerIndex=362|OwnerPartId=1|FormalType=1|PinConglomerate=56|PinLength=30|Location.X=550|Location.Y=838|Name=32|Designator=A-32|PinPropagationDelay=0.000000E+000
|RECORD=2|OwnerIndex=362|OwnerPartId=1|FormalType=1|PinConglomerate=58|PinLength=30|Location.X=490|Location.Y=828|Name=33|Designator=A-33|PinPropagationDelay=0.000000E+000
|RECORD=2|OwnerIndex=362|OwnerPartId=1|FormalType=1|PinConglomerate=56|PinLength=30|Location.X=550|Location.Y=828|Name=34|Designator=A-34|PinPropagationDelay=0.000000E+000
|RECORD=2|OwnerIndex=362|OwnerPartId=1|FormalType=1|PinConglomerate=58|PinLength=30|Location.X=490|Location.Y=818|Name=35|Designator=A-35|PinPropagationDelay=0.000000E+000
|RECORD=2|OwnerIndex=362|OwnerPartId=1|FormalType=1|PinConglomerate=56|PinLength=30|Location.X=550|Location.Y=818|Name=36|Designator=A-36|PinPropagationDelay=0.000000E+000
|RECORD=2|OwnerIndex=362|OwnerPartId=1|FormalType=1|PinConglomerate=58|PinLength=30|Location.X=490|Location.Y=808|Name=37|Designator=A-37|PinPropagationDelay=0.000000E+000
|RECORD=2|OwnerIndex=362|OwnerPartId=1|FormalType=1|PinConglomerate=56|PinLength=30|Location.X=550|Location.Y=808|Name=38|Designator=A-38|PinPropagationDelay=0.000000E+000
|RECORD=2|OwnerIndex=362|OwnerPartId=1|FormalType=1|PinConglomerate=58|PinLength=30|Location.X=490|Location.Y=798|Name=39|Designator=A-39|PinPropagationDelay=0.000000E+000
|RECORD=2|OwnerIndex=362|OwnerPartId=1|FormalType=1|PinConglomerate=56|PinLength=30|Location.X=550|Location.Y=798|Name=40|Designator=A-40|PinPropagationDelay=0.000000E+000
|RECORD=2|OwnerIndex=362|OwnerPartId=1|FormalType=1|PinConglomerate=58|PinLength=30|Location.X=490|Location.Y=788|Name=41|Designator=A-41|PinPropagationDelay=0.000000E+000
|RECORD=2|OwnerIndex=362|OwnerPartId=1|FormalType=1|PinConglomerate=56|PinLength=30|Location.X=550|Location.Y=788|Name=42|Designator=A-42|PinPropagationDelay=0.000000E+000
|RECORD=2|OwnerIndex=362|OwnerPartId=1|FormalType=1|PinConglomerate=58|PinLength=30|Location.X=490|Location.Y=778|Name=43|Designator=A-43|PinPropagationDelay=0.000000E+000
|RECORD=2|OwnerIndex=362|OwnerPartId=1|FormalType=1|PinConglomerate=56|PinLength=30|Location.X=550|Location.Y=778|Name=44|Designator=A-44|PinPropagationDelay=0.000000E+000
|RECORD=2|OwnerIndex=362|OwnerPartId=1|FormalType=1|PinConglomerate=58|PinLength=30|Location.X=490|Location.Y=768|Name=45|Designator=A-45|PinPropagationDelay=0.000000E+000
|RECORD=2|OwnerIndex=362|OwnerPartId=1|FormalType=1|PinConglomerate=56|PinLength=30|Location.X=550|Location.Y=768|Name=46|Designator=A-46|PinPropagationDelay=0.000000E+000
|RECORD=2|OwnerIndex=362|OwnerPartId=1|FormalType=1|PinConglomerate=58|PinLength=30|Location.X=490|Location.Y=758|Name=47|Designator=A-47|PinPropagationDelay=0.000000E+000
|RECORD=2|OwnerIndex=362|OwnerPartId=1|FormalType=1|PinConglomerate=56|PinLength=30|Location.X=550|Location.Y=758|Name=48|Designator=A-48|PinPropagationDelay=0.000000E+000
|RECORD=2|OwnerIndex=362|OwnerPartId=1|FormalType=1|PinConglomerate=58|PinLength=30|Location.X=490|Location.Y=748|Name=49|Designator=A-49|PinPropagationDelay=0.000000E+000
|RECORD=2|OwnerIndex=362|OwnerPartId=1|FormalType=1|PinConglomerate=56|PinLength=30|Location.X=550|Location.Y=748|Name=50|Designator=A-50|PinPropagationDelay=0.000000E+000
|RECORD=2|OwnerIndex=362|OwnerPartId=1|FormalType=1|PinConglomerate=58|PinLength=30|Location.X=490|Location.Y=738|Name=51|Designator=A-51|PinPropagationDelay=0.000000E+000
|RECORD=2|OwnerIndex=362|OwnerPartId=1|FormalType=1|PinConglomerate=56|PinLength=30|Location.X=550|Location.Y=738|Name=52|Designator=A-52|PinPropagationDelay=0.000000E+000
|RECORD=2|OwnerIndex=362|OwnerPartId=1|FormalType=1|PinConglomerate=58|PinLength=30|Location.X=490|Location.Y=728|Name=53|Designator=A-53|PinPropagationDelay=0.000000E+000
|RECORD=2|OwnerIndex=362|OwnerPartId=1|FormalType=1|PinConglomerate=56|PinLength=30|Location.X=550|Location.Y=728|Name=54|Designator=A-54|PinPropagationDelay=0.000000E+000
|RECORD=2|OwnerIndex=362|OwnerPartId=1|FormalType=1|PinConglomerate=58|PinLength=30|Location.X=490|Location.Y=718|Name=55|Designator=A-55|PinPropagationDelay=0.000000E+000
|RECORD=2|OwnerIndex=362|OwnerPartId=1|FormalType=1|PinConglomerate=56|PinLength=30|Location.X=550|Location.Y=718|Name=56|Designator=A-56|PinPropagationDelay=0.000000E+000
|RECORD=2|OwnerIndex=362|OwnerPartId=1|FormalType=1|PinConglomerate=58|PinLength=30|Location.X=490|Location.Y=708|Name=57|Designator=A-57|PinPropagationDelay=0.000000E+000
|RECORD=2|OwnerIndex=362|OwnerPartId=1|FormalType=1|PinConglomerate=56|PinLength=30|Location.X=550|Location.Y=708|Name=58|Designator=A-58|PinPropagationDelay=0.000000E+000
|RECORD=2|OwnerIndex=362|OwnerPartId=1|FormalType=1|PinConglomerate=58|PinLength=30|Location.X=490|Location.Y=698|Name=59|Designator=A-59|PinPropagationDelay=0.000000E+000
|RECORD=2|OwnerIndex=362|OwnerPartId=1|FormalType=1|PinConglomerate=56|PinLength=30|Location.X=550|Location.Y=698|Name=60|Designator=A-60|PinPropagationDelay=0.000000E+000
|RECORD=2|OwnerIndex=362|OwnerPartId=1|FormalType=1|PinConglomerate=58|PinLength=30|Location.X=490|Location.Y=688|Name=61|Designator=A-61|PinPropagationDelay=0.000000E+000
|RECORD=2|OwnerIndex=362|OwnerPartId=1|FormalType=1|PinConglomerate=56|PinLength=30|Location.X=550|Location.Y=688|Name=62|Designator=A-62|PinPropagationDelay=0.000000E+000
|RECORD=2|OwnerIndex=362|OwnerPartId=1|FormalType=1|PinConglomerate=58|PinLength=30|Location.X=490|Location.Y=678|Name=63|Designator=A-63|PinPropagationDelay=0.000000E+000
|RECORD=2|OwnerIndex=362|OwnerPartId=1|FormalType=1|PinConglomerate=56|PinLength=30|Location.X=550|Location.Y=678|Name=64|Designator=A-64|PinPropagationDelay=0.000000E+000
|RECORD=2|OwnerIndex=362|OwnerPartId=1|FormalType=1|PinConglomerate=58|PinLength=30|Location.X=490|Location.Y=668|Name=65|Designator=A-65|PinPropagationDelay=0.000000E+000
|RECORD=2|OwnerIndex=362|OwnerPartId=1|FormalType=1|PinConglomerate=56|PinLength=30|Location.X=550|Location.Y=668|Name=66|Designator=A-66|PinPropagationDelay=0.000000E+000
|RECORD=2|OwnerIndex=362|OwnerPartId=1|FormalType=1|PinConglomerate=58|PinLength=30|Location.X=490|Location.Y=658|Name=67|Designator=A-67|PinPropagationDelay=0.000000E+000
|RECORD=2|OwnerIndex=362|OwnerPartId=1|FormalType=1|PinConglomerate=56|PinLength=30|Location.X=550|Location.Y=658|Name=68|Designator=A-68|PinPropagationDelay=0.000000E+000
|RECORD=2|OwnerIndex=362|OwnerPartId=1|FormalType=1|PinConglomerate=58|PinLength=30|Location.X=490|Location.Y=648|Name=69|Designator=A-69|PinPropagationDelay=0.000000E+000
|RECORD=2|OwnerIndex=362|OwnerPartId=1|FormalType=1|PinConglomerate=56|PinLength=30|Location.X=550|Location.Y=648|Name=70|Designator=A-70|PinPropagationDelay=0.000000E+000
|RECORD=2|OwnerIndex=362|OwnerPartId=1|FormalType=1|PinConglomerate=58|PinLength=30|Location.X=490|Location.Y=638|Name=71|Designator=A-71|PinPropagationDelay=0.000000E+000
|RECORD=2|OwnerIndex=362|OwnerPartId=1|FormalType=1|PinConglomerate=56|PinLength=30|Location.X=550|Location.Y=638|Name=72|Designator=A-72|PinPropagationDelay=0.000000E+000
|RECORD=2|OwnerIndex=362|OwnerPartId=1|FormalType=1|PinConglomerate=58|PinLength=30|Location.X=490|Location.Y=628|Name=73|Designator=A-73|PinPropagationDelay=0.000000E+000
|RECORD=2|OwnerIndex=362|OwnerPartId=1|FormalType=1|PinConglomerate=56|PinLength=30|Location.X=550|Location.Y=628|Name=74|Designator=A-74|PinPropagationDelay=0.000000E+000
|RECORD=2|OwnerIndex=362|OwnerPartId=1|FormalType=1|PinConglomerate=58|PinLength=30|Location.X=490|Location.Y=618|Name=75|Designator=A-75|PinPropagationDelay=0.000000E+000
|RECORD=2|OwnerIndex=362|OwnerPartId=1|FormalType=1|PinConglomerate=56|PinLength=30|Location.X=550|Location.Y=618|Name=76|Designator=A-76|PinPropagationDelay=0.000000E+000
|RECORD=2|OwnerIndex=362|OwnerPartId=1|FormalType=1|PinConglomerate=58|PinLength=30|Location.X=490|Location.Y=608|Name=77|Designator=A-77|PinPropagationDelay=0.000000E+000
|RECORD=2|OwnerIndex=362|OwnerPartId=1|FormalType=1|PinConglomerate=56|PinLength=30|Location.X=550|Location.Y=608|Name=78|Designator=A-78|PinPropagationDelay=0.000000E+000
|RECORD=2|OwnerIndex=362|OwnerPartId=1|FormalType=1|PinConglomerate=58|PinLength=30|Location.X=490|Location.Y=598|Name=79|Designator=A-79|PinPropagationDelay=0.000000E+000
|RECORD=2|OwnerIndex=362|OwnerPartId=1|FormalType=1|PinConglomerate=56|PinLength=30|Location.X=550|Location.Y=598|Name=80|Designator=A-80|PinPropagationDelay=0.000000E+000
|RECORD=2|OwnerIndex=362|OwnerPartId=1|FormalType=1|PinConglomerate=58|PinLength=30|Location.X=490|Location.Y=588|Name=81|Designator=A-81|PinPropagationDelay=0.000000E+000
|RECORD=2|OwnerIndex=362|OwnerPartId=1|FormalType=1|PinConglomerate=56|PinLength=30|Location.X=550|Location.Y=588|Name=82|Designator=A-82|PinPropagationDelay=0.000000E+000
|RECORD=2|OwnerIndex=362|OwnerPartId=1|FormalType=1|PinConglomerate=58|PinLength=30|Location.X=490|Location.Y=578|Name=83|Designator=A-83|PinPropagationDelay=0.000000E+000
|RECORD=2|OwnerIndex=362|OwnerPartId=1|FormalType=1|PinConglomerate=56|PinLength=30|Location.X=550|Location.Y=578|Name=84|Designator=A-84|PinPropagationDelay=0.000000E+000
|RECORD=34|OwnerIndex=362|IndexInSheet=-1|OwnerPartId=-1|Location.X=490|Location.Y=998|Color=8388608|FontID=1|Text=P1|Name=Designator|ReadOnlyState=1
|RECORD=41|OwnerIndex=362|IndexInSheet=-1|OwnerPartId=-1|Location.X=490|Location.Y=558|Color=8388608|FontID=1|Text=FPGA_CONN|Name=Comment
|RECORD=44|OwnerIndex=362
|RECORD=45|OwnerIndex=1041|IndexInSheet=-1|ModelName=FPGA_CONN|ModelType=PCBLIB|DatafileCount=1|ModelDatafileEntity0=FPGA_CONN|ModelDatafileKind0=PCBLib|IsCurrent=T
|RECORD=46|OwnerIndex=1042
|RECORD=48|OwnerIndex=1042
|RECORD=1|LibReference=FPGA_CONN|PartCount=5|DisplayModeCount=1|IndexInSheet=334|OwnerPartId=-1|Location.X=1170|Location.Y=988|CurrentPartId=2|LibraryPath=*|SourceLibraryName=FPGA_CONN.SchLib|TargetFileName=*|AreaColor=11599871|Color=128|PartIDLocked=T|NotUseDBTableName=T|DesignItemId=FPGA_CONN|AllPinCount=336
|RECORD=14|OwnerIndex=1045|IsNotAccesible=T|OwnerPartId=2|Location.X=1200|Location.Y=568|Corner.X=1260|Corner.Y=998|Color=128|AreaColor=11599871|IsSolid=T
|RECORD=2|OwnerIndex=1045|OwnerPartId=2|FormalType=1|PinConglomerate=58|PinLength=30|Location.X=1200|Location.Y=988|Name=1|Designator=B-1|PinPropagationDelay=0.000000E+000
|RECORD=2|OwnerIndex=1045|OwnerPartId=2|FormalType=1|PinConglomerate=56|PinLength=30|Location.X=1260|Location.Y=988|Name=2|Designator=B-2|PinPropagationDelay=0.000000E+000
|RECORD=2|OwnerIndex=1045|OwnerPartId=2|FormalType=1|PinConglomerate=58|PinLength=30|Location.X=1200|Location.Y=978|Name=3|Designator=B-3|PinPropagationDelay=0.000000E+000
|RECORD=2|OwnerIndex=1045|OwnerPartId=2|FormalType=1|PinConglomerate=56|PinLength=30|Location.X=1260|Location.Y=978|Name=4|Designator=B-4|PinPropagationDelay=0.000000E+000
|RECORD=2|OwnerIndex=1045|OwnerPartId=2|FormalType=1|PinConglomerate=58|PinLength=30|Location.X=1200|Location.Y=968|Name=5|Designator=B-5|PinPropagationDelay=0.000000E+000
|RECORD=2|OwnerIndex=1045|OwnerPartId=2|FormalType=1|PinConglomerate=56|PinLength=30|Location.X=1260|Location.Y=968|Name=6|Designator=B-6|PinPropagationDelay=0.000000E+000
|RECORD=2|OwnerIndex=1045|OwnerPartId=2|FormalType=1|PinConglomerate=58|PinLength=30|Location.X=1200|Location.Y=958|Name=7|Designator=B-7|PinPropagationDelay=0.000000E+000
|RECORD=2|OwnerIndex=1045|OwnerPartId=2|FormalType=1|PinConglomerate=56|PinLength=30|Location.X=1260|Location.Y=958|Name=8|Designator=B-8|PinPropagationDelay=0.000000E+000
|RECORD=2|OwnerIndex=1045|OwnerPartId=2|FormalType=1|PinConglomerate=58|PinLength=30|Location.X=1200|Location.Y=948|Name=9|Designator=B-9|PinPropagationDelay=0.000000E+000
|RECORD=2|OwnerIndex=1045|OwnerPartId=2|FormalType=1|PinConglomerate=56|PinLength=30|Location.X=1260|Location.Y=948|Name=10|Designator=B-10|PinPropagationDelay=0.000000E+000
|RECORD=2|OwnerIndex=1045|OwnerPartId=2|FormalType=1|PinConglomerate=58|PinLength=30|Location.X=1200|Location.Y=938|Name=11|Designator=B-11|PinPropagationDelay=0.000000E+000
|RECORD=2|OwnerIndex=1045|OwnerPartId=2|FormalType=1|PinConglomerate=56|PinLength=30|Location.X=1260|Location.Y=938|Name=12|Designator=B-12|PinPropagationDelay=0.000000E+000
|RECORD=2|OwnerIndex=1045|OwnerPartId=2|FormalType=1|PinConglomerate=58|PinLength=30|Location.X=1200|Location.Y=928|Name=13|Designator=B-13|PinPropagationDelay=0.000000E+000
|RECORD=2|OwnerIndex=1045|OwnerPartId=2|FormalType=1|PinConglomerate=56|PinLength=30|Location.X=1260|Location.Y=928|Name=14|Designator=B-14|PinPropagationDelay=0.000000E+000
|RECORD=2|OwnerIndex=1045|OwnerPartId=2|FormalType=1|PinConglomerate=58|PinLength=30|Location.X=1200|Location.Y=918|Name=15|Designator=B-15|PinPropagationDelay=0.000000E+000
|RECORD=2|OwnerIndex=1045|OwnerPartId=2|FormalType=1|PinConglomerate=56|PinLength=30|Location.X=1260|Location.Y=918|Name=16|Designator=B-16|PinPropagationDelay=0.000000E+000
|RECORD=2|OwnerIndex=1045|OwnerPartId=2|FormalType=1|PinConglomerate=58|PinLength=30|Location.X=1200|Location.Y=908|Name=17|Designator=B-17|PinPropagationDelay=0.000000E+000
|RECORD=2|OwnerIndex=1045|OwnerPartId=2|FormalType=1|PinConglomerate=56|PinLength=30|Location.X=1260|Location.Y=908|Name=18|Designator=B-18|PinPropagationDelay=0.000000E+000
|RECORD=2|OwnerIndex=1045|OwnerPartId=2|FormalType=1|PinConglomerate=58|PinLength=30|Location.X=1200|Location.Y=898|Name=19|Designator=B-19|PinPropagationDelay=0.000000E+000
|RECORD=2|OwnerIndex=1045|OwnerPartId=2|FormalType=1|PinConglomerate=56|PinLength=30|Location.X=1260|Location.Y=898|Name=20|Designator=B-20|PinPropagationDelay=0.000000E+000
|RECORD=2|OwnerIndex=1045|OwnerPartId=2|FormalType=1|PinConglomerate=58|PinLength=30|Location.X=1200|Location.Y=888|Name=21|Designator=B-21|PinPropagationDelay=0.000000E+000
|RECORD=2|OwnerIndex=1045|OwnerPartId=2|FormalType=1|PinConglomerate=56|PinLength=30|Location.X=1260|Location.Y=888|Name=22|Designator=B-22|PinPropagationDelay=0.000000E+000
|RECORD=2|OwnerIndex=1045|OwnerPartId=2|FormalType=1|PinConglomerate=58|PinLength=30|Location.X=1200|Location.Y=878|Name=23|Designator=B-23|PinPropagationDelay=0.000000E+000
|RECORD=2|OwnerIndex=1045|OwnerPartId=2|FormalType=1|PinConglomerate=56|PinLength=30|Location.X=1260|Location.Y=878|Name=24|Designator=B-24|PinPropagationDelay=0.000000E+000
|RECORD=2|OwnerIndex=1045|OwnerPartId=2|FormalType=1|PinConglomerate=58|PinLength=30|Location.X=1200|Location.Y=868|Name=25|Designator=B-25|PinPropagationDelay=0.000000E+000
|RECORD=2|OwnerIndex=1045|OwnerPartId=2|FormalType=1|PinConglomerate=56|PinLength=30|Location.X=1260|Location.Y=868|Name=26|Designator=B-26|PinPropagationDelay=0.000000E+000
|RECORD=2|OwnerIndex=1045|OwnerPartId=2|FormalType=1|PinConglomerate=58|PinLength=30|Location.X=1200|Location.Y=858|Name=27|Designator=B-27|PinPropagationDelay=0.000000E+000
|RECORD=2|OwnerIndex=1045|OwnerPartId=2|FormalType=1|PinConglomerate=56|PinLength=30|Location.X=1260|Location.Y=858|Name=28|Designator=B-28|PinPropagationDelay=0.000000E+000
|RECORD=2|OwnerIndex=1045|OwnerPartId=2|FormalType=1|PinConglomerate=58|PinLength=30|Location.X=1200|Location.Y=848|Name=29|Designator=B-29|PinPropagationDelay=0.000000E+000
|RECORD=2|OwnerIndex=1045|OwnerPartId=2|FormalType=1|PinConglomerate=56|PinLength=30|Location.X=1260|Location.Y=848|Name=30|Designator=B-30|PinPropagationDelay=0.000000E+000
|RECORD=2|OwnerIndex=1045|OwnerPartId=2|FormalType=1|PinConglomerate=58|PinLength=30|Location.X=1200|Location.Y=838|Name=31|Designator=B-31|PinPropagationDelay=0.000000E+000
|RECORD=2|OwnerIndex=1045|OwnerPartId=2|FormalType=1|PinConglomerate=56|PinLength=30|Location.X=1260|Location.Y=838|Name=32|Designator=B-32|PinPropagationDelay=0.000000E+000
|RECORD=2|OwnerIndex=1045|OwnerPartId=2|FormalType=1|PinConglomerate=58|PinLength=30|Location.X=1200|Location.Y=828|Name=33|Designator=B-33|PinPropagationDelay=0.000000E+000
|RECORD=2|OwnerIndex=1045|OwnerPartId=2|FormalType=1|PinConglomerate=56|PinLength=30|Location.X=1260|Location.Y=828|Name=34|Designator=B-34|PinPropagationDelay=0.000000E+000
|RECORD=2|OwnerIndex=1045|OwnerPartId=2|FormalType=1|PinConglomerate=58|PinLength=30|Location.X=1200|Location.Y=818|Name=35|Designator=B-35|PinPropagationDelay=0.000000E+000
|RECORD=2|OwnerIndex=1045|OwnerPartId=2|FormalType=1|PinConglomerate=56|PinLength=30|Location.X=1260|Location.Y=818|Name=36|Designator=B-36|PinPropagationDelay=0.000000E+000
|RECORD=2|OwnerIndex=1045|OwnerPartId=2|FormalType=1|PinConglomerate=58|PinLength=30|Location.X=1200|Location.Y=808|Name=37|Designator=B-37|PinPropagationDelay=0.000000E+000
|RECORD=2|OwnerIndex=1045|OwnerPartId=2|FormalType=1|PinConglomerate=56|PinLength=30|Location.X=1260|Location.Y=808|Name=38|Designator=B-38|PinPropagationDelay=0.000000E+000
|RECORD=2|OwnerIndex=1045|OwnerPartId=2|FormalType=1|PinConglomerate=58|PinLength=30|Location.X=1200|Location.Y=798|Name=39|Designator=B-39|PinPropagationDelay=0.000000E+000
|RECORD=2|OwnerIndex=1045|OwnerPartId=2|FormalType=1|PinConglomerate=56|PinLength=30|Location.X=1260|Location.Y=798|Name=40|Designator=B-40|PinPropagationDelay=0.000000E+000
|RECORD=2|OwnerIndex=1045|OwnerPartId=2|FormalType=1|PinConglomerate=58|PinLength=30|Location.X=1200|Location.Y=788|Name=41|Designator=B-41|PinPropagationDelay=0.000000E+000
|RECORD=2|OwnerIndex=1045|OwnerPartId=2|FormalType=1|PinConglomerate=56|PinLength=30|Location.X=1260|Location.Y=788|Name=42|Designator=B-42|PinPropagationDelay=0.000000E+000
|RECORD=2|OwnerIndex=1045|OwnerPartId=2|FormalType=1|PinConglomerate=58|PinLength=30|Location.X=1200|Location.Y=778|Name=43|Designator=B-43|PinPropagationDelay=0.000000E+000
|RECORD=2|OwnerIndex=1045|OwnerPartId=2|FormalType=1|PinConglomerate=56|PinLength=30|Location.X=1260|Location.Y=778|Name=44|Designator=B-44|PinPropagationDelay=0.000000E+000
|RECORD=2|OwnerIndex=1045|OwnerPartId=2|FormalType=1|PinConglomerate=58|PinLength=30|Location.X=1200|Location.Y=768|Name=45|Designator=B-45|PinPropagationDelay=0.000000E+000
|RECORD=2|OwnerIndex=1045|OwnerPartId=2|FormalType=1|PinConglomerate=56|PinLength=30|Location.X=1260|Location.Y=768|Name=46|Designator=B-46|PinPropagationDelay=0.000000E+000
|RECORD=2|OwnerIndex=1045|OwnerPartId=2|FormalType=1|PinConglomerate=58|PinLength=30|Location.X=1200|Location.Y=758|Name=47|Designator=B-47|PinPropagationDelay=0.000000E+000
|RECORD=2|OwnerIndex=1045|OwnerPartId=2|FormalType=1|PinConglomerate=56|PinLength=30|Location.X=1260|Location.Y=758|Name=48|Designator=B-48|PinPropagationDelay=0.000000E+000
|RECORD=2|OwnerIndex=1045|OwnerPartId=2|FormalType=1|PinConglomerate=58|PinLength=30|Location.X=1200|Location.Y=748|Name=49|Designator=B-49|PinPropagationDelay=0.000000E+000
|RECORD=2|OwnerIndex=1045|OwnerPartId=2|FormalType=1|PinConglomerate=56|PinLength=30|Location.X=1260|Location.Y=748|Name=50|Designator=B-50|PinPropagationDelay=0.000000E+000
|RECORD=2|OwnerIndex=1045|OwnerPartId=2|FormalType=1|PinConglomerate=58|PinLength=30|Location.X=1200|Location.Y=738|Name=51|Designator=B-51|PinPropagationDelay=0.000000E+000
|RECORD=2|OwnerIndex=1045|OwnerPartId=2|FormalType=1|PinConglomerate=56|PinLength=30|Location.X=1260|Location.Y=738|Name=52|Designator=B-52|PinPropagationDelay=0.000000E+000
|RECORD=2|OwnerIndex=1045|OwnerPartId=2|FormalType=1|PinConglomerate=58|PinLength=30|Location.X=1200|Location.Y=728|Name=53|Designator=B-53|PinPropagationDelay=0.000000E+000
|RECORD=2|OwnerIndex=1045|OwnerPartId=2|FormalType=1|PinConglomerate=56|PinLength=30|Location.X=1260|Location.Y=728|Name=54|Designator=B-54|PinPropagationDelay=0.000000E+000
|RECORD=2|OwnerIndex=1045|OwnerPartId=2|FormalType=1|PinConglomerate=58|PinLength=30|Location.X=1200|Location.Y=718|Name=55|Designator=B-55|PinPropagationDelay=0.000000E+000
|RECORD=2|OwnerIndex=1045|OwnerPartId=2|FormalType=1|PinConglomerate=56|PinLength=30|Location.X=1260|Location.Y=718|Name=56|Designator=B-56|PinPropagationDelay=0.000000E+000
|RECORD=2|OwnerIndex=1045|OwnerPartId=2|FormalType=1|PinConglomerate=58|PinLength=30|Location.X=1200|Location.Y=708|Name=57|Designator=B-57|PinPropagationDelay=0.000000E+000
|RECORD=2|OwnerIndex=1045|OwnerPartId=2|FormalType=1|PinConglomerate=56|PinLength=30|Location.X=1260|Location.Y=708|Name=58|Designator=B-58|PinPropagationDelay=0.000000E+000
|RECORD=2|OwnerIndex=1045|OwnerPartId=2|FormalType=1|PinConglomerate=58|PinLength=30|Location.X=1200|Location.Y=698|Name=59|Designator=B-59|PinPropagationDelay=0.000000E+000
|RECORD=2|OwnerIndex=1045|OwnerPartId=2|FormalType=1|PinConglomerate=56|PinLength=30|Location.X=1260|Location.Y=698|Name=60|Designator=B-60|PinPropagationDelay=0.000000E+000
|RECORD=2|OwnerIndex=1045|OwnerPartId=2|FormalType=1|PinConglomerate=58|PinLength=30|Location.X=1200|Location.Y=688|Name=61|Designator=B-61|PinPropagationDelay=0.000000E+000
|RECORD=2|OwnerIndex=1045|OwnerPartId=2|FormalType=1|PinConglomerate=56|PinLength=30|Location.X=1260|Location.Y=688|Name=62|Designator=B-62|PinPropagationDelay=0.000000E+000
|RECORD=2|OwnerIndex=1045|OwnerPartId=2|FormalType=1|PinConglomerate=58|PinLength=30|Location.X=1200|Location.Y=678|Name=63|Designator=B-63|PinPropagationDelay=0.000000E+000
|RECORD=2|OwnerIndex=1045|OwnerPartId=2|FormalType=1|PinConglomerate=56|PinLength=30|Location.X=1260|Location.Y=678|Name=64|Designator=B-64|PinPropagationDelay=0.000000E+000
|RECORD=2|OwnerIndex=1045|OwnerPartId=2|FormalType=1|PinConglomerate=58|PinLength=30|Location.X=1200|Location.Y=668|Name=65|Designator=B-65|PinPropagationDelay=0.000000E+000
|RECORD=2|OwnerIndex=1045|OwnerPartId=2|FormalType=1|PinConglomerate=56|PinLength=30|Location.X=1260|Location.Y=668|Name=66|Designator=B-66|PinPropagationDelay=0.000000E+000
|RECORD=2|OwnerIndex=1045|OwnerPartId=2|FormalType=1|PinConglomerate=58|PinLength=30|Location.X=1200|Location.Y=658|Name=67|Designator=B-67|PinPropagationDelay=0.000000E+000
|RECORD=2|OwnerIndex=1045|OwnerPartId=2|FormalType=1|PinConglomerate=56|PinLength=30|Location.X=1260|Location.Y=658|Name=68|Designator=B-68|PinPropagationDelay=0.000000E+000
|RECORD=2|OwnerIndex=1045|OwnerPartId=2|FormalType=1|PinConglomerate=58|PinLength=30|Location.X=1200|Location.Y=648|Name=69|Designator=B-69|PinPropagationDelay=0.000000E+000
|RECORD=2|OwnerIndex=1045|OwnerPartId=2|FormalType=1|PinConglomerate=56|PinLength=30|Location.X=1260|Location.Y=648|Name=70|Designator=B-70|PinPropagationDelay=0.000000E+000
|RECORD=2|OwnerIndex=1045|OwnerPartId=2|FormalType=1|PinConglomerate=58|PinLength=30|Location.X=1200|Location.Y=638|Name=71|Designator=B-71|PinPropagationDelay=0.000000E+000
|RECORD=2|OwnerIndex=1045|OwnerPartId=2|FormalType=1|PinConglomerate=56|PinLength=30|Location.X=1260|Location.Y=638|Name=72|Designator=B-72|PinPropagationDelay=0.000000E+000
|RECORD=2|OwnerIndex=1045|OwnerPartId=2|FormalType=1|PinConglomerate=58|PinLength=30|Location.X=1200|Location.Y=628|Name=73|Designator=B-73|PinPropagationDelay=0.000000E+000
|RECORD=2|OwnerIndex=1045|OwnerPartId=2|FormalType=1|PinConglomerate=56|PinLength=30|Location.X=1260|Location.Y=628|Name=74|Designator=B-74|PinPropagationDelay=0.000000E+000
|RECORD=2|OwnerIndex=1045|OwnerPartId=2|FormalType=1|PinConglomerate=58|PinLength=30|Location.X=1200|Location.Y=618|Name=75|Designator=B-75|PinPropagationDelay=0.000000E+000
|RECORD=2|OwnerIndex=1045|OwnerPartId=2|FormalType=1|PinConglomerate=56|PinLength=30|Location.X=1260|Location.Y=618|Name=76|Designator=B-76|PinPropagationDelay=0.000000E+000
|RECORD=2|OwnerIndex=1045|OwnerPartId=2|FormalType=1|PinConglomerate=58|PinLength=30|Location.X=1200|Location.Y=608|Name=77|Designator=B-77|PinPropagationDelay=0.000000E+000
|RECORD=2|OwnerIndex=1045|OwnerPartId=2|FormalType=1|PinConglomerate=56|PinLength=30|Location.X=1260|Location.Y=608|Name=78|Designator=B-78|PinPropagationDelay=0.000000E+000
|RECORD=2|OwnerIndex=1045|OwnerPartId=2|FormalType=1|PinConglomerate=58|PinLength=30|Location.X=1200|Location.Y=598|Name=79|Designator=B-79|PinPropagationDelay=0.000000E+000
|RECORD=2|OwnerIndex=1045|OwnerPartId=2|FormalType=1|PinConglomerate=56|PinLength=30|Location.X=1260|Location.Y=598|Name=80|Designator=B-80|PinPropagationDelay=0.000000E+000
|RECORD=2|OwnerIndex=1045|OwnerPartId=2|FormalType=1|PinConglomerate=58|PinLength=30|Location.X=1200|Location.Y=588|Name=81|Designator=B-81|PinPropagationDelay=0.000000E+000
|RECORD=2|OwnerIndex=1045|OwnerPartId=2|FormalType=1|PinConglomerate=56|PinLength=30|Location.X=1260|Location.Y=588|Name=82|Designator=B-82|PinPropagationDelay=0.000000E+000
|RECORD=2|OwnerIndex=1045|OwnerPartId=2|FormalType=1|PinConglomerate=58|PinLength=30|Location.X=1200|Location.Y=578|Name=83|Designator=B-83|PinPropagationDelay=0.000000E+000
|RECORD=2|OwnerIndex=1045|OwnerPartId=2|FormalType=1|PinConglomerate=56|PinLength=30|Location.X=1260|Location.Y=578|Name=84|Designator=B-84|PinPropagationDelay=0.000000E+000
|RECORD=14|OwnerIndex=1045|IsNotAccesible=T|IndexInSheet=85|OwnerPartId=3|Location.X=1200|Location.Y=568|Corner.X=1260|Corner.Y=998|Color=128|AreaColor=11599871|IsSolid=T
|RECORD=2|OwnerIndex=1045|OwnerPartId=3|FormalType=1|PinConglomerate=58|PinLength=30|Location.X=1200|Location.Y=988|Name=1|Designator=C-1|PinPropagationDelay=0.000000E+000
|RECORD=2|OwnerIndex=1045|OwnerPartId=3|FormalType=1|PinConglomerate=56|PinLength=30|Location.X=1260|Location.Y=988|Name=2|Designator=C-2|PinPropagationDelay=0.000000E+000
|RECORD=2|OwnerIndex=1045|OwnerPartId=3|FormalType=1|PinConglomerate=58|PinLength=30|Location.X=1200|Location.Y=978|Name=3|Designator=C-3|PinPropagationDelay=0.000000E+000
|RECORD=2|OwnerIndex=1045|OwnerPartId=3|FormalType=1|PinConglomerate=56|PinLength=30|Location.X=1260|Location.Y=978|Name=4|Designator=C-4|PinPropagationDelay=0.000000E+000
|RECORD=2|OwnerIndex=1045|OwnerPartId=3|FormalType=1|PinConglomerate=58|PinLength=30|Location.X=1200|Location.Y=968|Name=5|Designator=C-5|PinPropagationDelay=0.000000E+000
|RECORD=2|OwnerIndex=1045|OwnerPartId=3|FormalType=1|PinConglomerate=56|PinLength=30|Location.X=1260|Location.Y=968|Name=6|Designator=C-6|PinPropagationDelay=0.000000E+000
|RECORD=2|OwnerIndex=1045|OwnerPartId=3|FormalType=1|PinConglomerate=58|PinLength=30|Location.X=1200|Location.Y=958|Name=7|Designator=C-7|PinPropagationDelay=0.000000E+000
|RECORD=2|OwnerIndex=1045|OwnerPartId=3|FormalType=1|PinConglomerate=56|PinLength=30|Location.X=1260|Location.Y=958|Name=8|Designator=C-8|PinPropagationDelay=0.000000E+000
|RECORD=2|OwnerIndex=1045|OwnerPartId=3|FormalType=1|PinConglomerate=58|PinLength=30|Location.X=1200|Location.Y=948|Name=9|Designator=C-9|PinPropagationDelay=0.000000E+000
|RECORD=2|OwnerIndex=1045|OwnerPartId=3|FormalType=1|PinConglomerate=56|PinLength=30|Location.X=1260|Location.Y=948|Name=10|Designator=C-10|PinPropagationDelay=0.000000E+000
|RECORD=2|OwnerIndex=1045|OwnerPartId=3|FormalType=1|PinConglomerate=58|PinLength=30|Location.X=1200|Location.Y=938|Name=11|Designator=C-11|PinPropagationDelay=0.000000E+000
|RECORD=2|OwnerIndex=1045|OwnerPartId=3|FormalType=1|PinConglomerate=56|PinLength=30|Location.X=1260|Location.Y=938|Name=12|Designator=C-12|PinPropagationDelay=0.000000E+000
|RECORD=2|OwnerIndex=1045|OwnerPartId=3|FormalType=1|PinConglomerate=58|PinLength=30|Location.X=1200|Location.Y=928|Name=13|Designator=C-13|PinPropagationDelay=0.000000E+000
|RECORD=2|OwnerIndex=1045|OwnerPartId=3|FormalType=1|PinConglomerate=56|PinLength=30|Location.X=1260|Location.Y=928|Name=14|Designator=C-14|PinPropagationDelay=0.000000E+000
|RECORD=2|OwnerIndex=1045|OwnerPartId=3|FormalType=1|PinConglomerate=58|PinLength=30|Location.X=1200|Location.Y=918|Name=15|Designator=C-15|PinPropagationDelay=0.000000E+000
|RECORD=2|OwnerIndex=1045|OwnerPartId=3|FormalType=1|PinConglomerate=56|PinLength=30|Location.X=1260|Location.Y=918|Name=16|Designator=C-16|PinPropagationDelay=0.000000E+000
|RECORD=2|OwnerIndex=1045|OwnerPartId=3|FormalType=1|PinConglomerate=58|PinLength=30|Location.X=1200|Location.Y=908|Name=17|Designator=C-17|PinPropagationDelay=0.000000E+000
|RECORD=2|OwnerIndex=1045|OwnerPartId=3|FormalType=1|PinConglomerate=56|PinLength=30|Location.X=1260|Location.Y=908|Name=18|Designator=C-18|PinPropagationDelay=0.000000E+000
|RECORD=2|OwnerIndex=1045|OwnerPartId=3|FormalType=1|PinConglomerate=58|PinLength=30|Location.X=1200|Location.Y=898|Name=19|Designator=C-19|PinPropagationDelay=0.000000E+000
|RECORD=2|OwnerIndex=1045|OwnerPartId=3|FormalType=1|PinConglomerate=56|PinLength=30|Location.X=1260|Location.Y=898|Name=20|Designator=C-20|PinPropagationDelay=0.000000E+000
|RECORD=2|OwnerIndex=1045|OwnerPartId=3|FormalType=1|PinConglomerate=58|PinLength=30|Location.X=1200|Location.Y=888|Name=21|Designator=C-21|PinPropagationDelay=0.000000E+000
|RECORD=2|OwnerIndex=1045|OwnerPartId=3|FormalType=1|PinConglomerate=56|PinLength=30|Location.X=1260|Location.Y=888|Name=22|Designator=C-22|PinPropagationDelay=0.000000E+000
|RECORD=2|OwnerIndex=1045|OwnerPartId=3|FormalType=1|PinConglomerate=58|PinLength=30|Location.X=1200|Location.Y=878|Name=23|Designator=C-23|PinPropagationDelay=0.000000E+000
|RECORD=2|OwnerIndex=1045|OwnerPartId=3|FormalType=1|PinConglomerate=56|PinLength=30|Location.X=1260|Location.Y=878|Name=24|Designator=C-24|PinPropagationDelay=0.000000E+000
|RECORD=2|OwnerIndex=1045|OwnerPartId=3|FormalType=1|PinConglomerate=58|PinLength=30|Location.X=1200|Location.Y=868|Name=25|Designator=C-25|PinPropagationDelay=0.000000E+000
|RECORD=2|OwnerIndex=1045|OwnerPartId=3|FormalType=1|PinConglomerate=56|PinLength=30|Location.X=1260|Location.Y=868|Name=26|Designator=C-26|PinPropagationDelay=0.000000E+000
|RECORD=2|OwnerIndex=1045|OwnerPartId=3|FormalType=1|PinConglomerate=58|PinLength=30|Location.X=1200|Location.Y=858|Name=27|Designator=C-27|PinPropagationDelay=0.000000E+000
|RECORD=2|OwnerIndex=1045|OwnerPartId=3|FormalType=1|PinConglomerate=56|PinLength=30|Location.X=1260|Location.Y=858|Name=28|Designator=C-28|PinPropagationDelay=0.000000E+000
|RECORD=2|OwnerIndex=1045|OwnerPartId=3|FormalType=1|PinConglomerate=58|PinLength=30|Location.X=1200|Location.Y=848|Name=29|Designator=C-29|PinPropagationDelay=0.000000E+000
|RECORD=2|OwnerIndex=1045|OwnerPartId=3|FormalType=1|PinConglomerate=56|PinLength=30|Location.X=1260|Location.Y=848|Name=30|Designator=C-30|PinPropagationDelay=0.000000E+000
|RECORD=2|OwnerIndex=1045|OwnerPartId=3|FormalType=1|PinConglomerate=58|PinLength=30|Location.X=1200|Location.Y=838|Name=31|Designator=C-31|PinPropagationDelay=0.000000E+000
|RECORD=2|OwnerIndex=1045|OwnerPartId=3|FormalType=1|PinConglomerate=56|PinLength=30|Location.X=1260|Location.Y=838|Name=32|Designator=C-32|PinPropagationDelay=0.000000E+000
|RECORD=2|OwnerIndex=1045|OwnerPartId=3|FormalType=1|PinConglomerate=58|PinLength=30|Location.X=1200|Location.Y=828|Name=33|Designator=C-33|PinPropagationDelay=0.000000E+000
|RECORD=2|OwnerIndex=1045|OwnerPartId=3|FormalType=1|PinConglomerate=56|PinLength=30|Location.X=1260|Location.Y=828|Name=34|Designator=C-34|PinPropagationDelay=0.000000E+000
|RECORD=2|OwnerIndex=1045|OwnerPartId=3|FormalType=1|PinConglomerate=58|PinLength=30|Location.X=1200|Location.Y=818|Name=35|Designator=C-35|PinPropagationDelay=0.000000E+000
|RECORD=2|OwnerIndex=1045|OwnerPartId=3|FormalType=1|PinConglomerate=56|PinLength=30|Location.X=1260|Location.Y=818|Name=36|Designator=C-36|PinPropagationDelay=0.000000E+000
|RECORD=2|OwnerIndex=1045|OwnerPartId=3|FormalType=1|PinConglomerate=58|PinLength=30|Location.X=1200|Location.Y=808|Name=37|Designator=C-37|PinPropagationDelay=0.000000E+000
|RECORD=2|OwnerIndex=1045|OwnerPartId=3|FormalType=1|PinConglomerate=56|PinLength=30|Location.X=1260|Location.Y=808|Name=38|Designator=C-38|PinPropagationDelay=0.000000E+000
|RECORD=2|OwnerIndex=1045|OwnerPartId=3|FormalType=1|PinConglomerate=58|PinLength=30|Location.X=1200|Location.Y=798|Name=39|Designator=C-39|PinPropagationDelay=0.000000E+000
|RECORD=2|OwnerIndex=1045|OwnerPartId=3|FormalType=1|PinConglomerate=56|PinLength=30|Location.X=1260|Location.Y=798|Name=40|Designator=C-40|PinPropagationDelay=0.000000E+000
|RECORD=2|OwnerIndex=1045|OwnerPartId=3|FormalType=1|PinConglomerate=58|PinLength=30|Location.X=1200|Location.Y=788|Name=41|Designator=C-41|PinPropagationDelay=0.000000E+000
|RECORD=2|OwnerIndex=1045|OwnerPartId=3|FormalType=1|PinConglomerate=56|PinLength=30|Location.X=1260|Location.Y=788|Name=42|Designator=C-42|PinPropagationDelay=0.000000E+000
|RECORD=2|OwnerIndex=1045|OwnerPartId=3|FormalType=1|PinConglomerate=58|PinLength=30|Location.X=1200|Location.Y=778|Name=43|Designator=C-43|PinPropagationDelay=0.000000E+000
|RECORD=2|OwnerIndex=1045|OwnerPartId=3|FormalType=1|PinConglomerate=56|PinLength=30|Location.X=1260|Location.Y=778|Name=44|Designator=C-44|PinPropagationDelay=0.000000E+000
|RECORD=2|OwnerIndex=1045|OwnerPartId=3|FormalType=1|PinConglomerate=58|PinLength=30|Location.X=1200|Location.Y=768|Name=45|Designator=C-45|PinPropagationDelay=0.000000E+000
|RECORD=2|OwnerIndex=1045|OwnerPartId=3|FormalType=1|PinConglomerate=56|PinLength=30|Location.X=1260|Location.Y=768|Name=46|Designator=C-46|PinPropagationDelay=0.000000E+000
|RECORD=2|OwnerIndex=1045|OwnerPartId=3|FormalType=1|PinConglomerate=58|PinLength=30|Location.X=1200|Location.Y=758|Name=47|Designator=C-47|PinPropagationDelay=0.000000E+000
|RECORD=2|OwnerIndex=1045|OwnerPartId=3|FormalType=1|PinConglomerate=56|PinLength=30|Location.X=1260|Location.Y=758|Name=48|Designator=C-48|PinPropagationDelay=0.000000E+000
|RECORD=2|OwnerIndex=1045|OwnerPartId=3|FormalType=1|PinConglomerate=58|PinLength=30|Location.X=1200|Location.Y=748|Name=49|Designator=C-49|PinPropagationDelay=0.000000E+000
|RECORD=2|OwnerIndex=1045|OwnerPartId=3|FormalType=1|PinConglomerate=56|PinLength=30|Location.X=1260|Location.Y=748|Name=50|Designator=C-50|PinPropagationDelay=0.000000E+000
|RECORD=2|OwnerIndex=1045|OwnerPartId=3|FormalType=1|PinConglomerate=58|PinLength=30|Location.X=1200|Location.Y=738|Name=51|Designator=C-51|PinPropagationDelay=0.000000E+000
|RECORD=2|OwnerIndex=1045|OwnerPartId=3|FormalType=1|PinConglomerate=56|PinLength=30|Location.X=1260|Location.Y=738|Name=52|Designator=C-52|PinPropagationDelay=0.000000E+000
|RECORD=2|OwnerIndex=1045|OwnerPartId=3|FormalType=1|PinConglomerate=58|PinLength=30|Location.X=1200|Location.Y=728|Name=53|Designator=C-53|PinPropagationDelay=0.000000E+000
|RECORD=2|OwnerIndex=1045|OwnerPartId=3|FormalType=1|PinConglomerate=56|PinLength=30|Location.X=1260|Location.Y=728|Name=54|Designator=C-54|PinPropagationDelay=0.000000E+000
|RECORD=2|OwnerIndex=1045|OwnerPartId=3|FormalType=1|PinConglomerate=58|PinLength=30|Location.X=1200|Location.Y=718|Name=55|Designator=C-55|PinPropagationDelay=0.000000E+000
|RECORD=2|OwnerIndex=1045|OwnerPartId=3|FormalType=1|PinConglomerate=56|PinLength=30|Location.X=1260|Location.Y=718|Name=56|Designator=C-56|PinPropagationDelay=0.000000E+000
|RECORD=2|OwnerIndex=1045|OwnerPartId=3|FormalType=1|PinConglomerate=58|PinLength=30|Location.X=1200|Location.Y=708|Name=57|Designator=C-57|PinPropagationDelay=0.000000E+000
|RECORD=2|OwnerIndex=1045|OwnerPartId=3|FormalType=1|PinConglomerate=56|PinLength=30|Location.X=1260|Location.Y=708|Name=58|Designator=C-58|PinPropagationDelay=0.000000E+000
|RECORD=2|OwnerIndex=1045|OwnerPartId=3|FormalType=1|PinConglomerate=58|PinLength=30|Location.X=1200|Location.Y=698|Name=59|Designator=C-59|PinPropagationDelay=0.000000E+000
|RECORD=2|OwnerIndex=1045|OwnerPartId=3|FormalType=1|PinConglomerate=56|PinLength=30|Location.X=1260|Location.Y=698|Name=60|Designator=C-60|PinPropagationDelay=0.000000E+000
|RECORD=2|OwnerIndex=1045|OwnerPartId=3|FormalType=1|PinConglomerate=58|PinLength=30|Location.X=1200|Location.Y=688|Name=61|Designator=C-61|PinPropagationDelay=0.000000E+000
|RECORD=2|OwnerIndex=1045|OwnerPartId=3|FormalType=1|PinConglomerate=56|PinLength=30|Location.X=1260|Location.Y=688|Name=62|Designator=C-62|PinPropagationDelay=0.000000E+000
|RECORD=2|OwnerIndex=1045|OwnerPartId=3|FormalType=1|PinConglomerate=58|PinLength=30|Location.X=1200|Location.Y=678|Name=63|Designator=C-63|PinPropagationDelay=0.000000E+000
|RECORD=2|OwnerIndex=1045|OwnerPartId=3|FormalType=1|PinConglomerate=56|PinLength=30|Location.X=1260|Location.Y=678|Name=64|Designator=C-64|PinPropagationDelay=0.000000E+000
|RECORD=2|OwnerIndex=1045|OwnerPartId=3|FormalType=1|PinConglomerate=58|PinLength=30|Location.X=1200|Location.Y=668|Name=65|Designator=C-65|PinPropagationDelay=0.000000E+000
|RECORD=2|OwnerIndex=1045|OwnerPartId=3|FormalType=1|PinConglomerate=56|PinLength=30|Location.X=1260|Location.Y=668|Name=66|Designator=C-66|PinPropagationDelay=0.000000E+000
|RECORD=2|OwnerIndex=1045|OwnerPartId=3|FormalType=1|PinConglomerate=58|PinLength=30|Location.X=1200|Location.Y=658|Name=67|Designator=C-67|PinPropagationDelay=0.000000E+000
|RECORD=2|OwnerIndex=1045|OwnerPartId=3|FormalType=1|PinConglomerate=56|PinLength=30|Location.X=1260|Location.Y=658|Name=68|Designator=C-68|PinPropagationDelay=0.000000E+000
|RECORD=2|OwnerIndex=1045|OwnerPartId=3|FormalType=1|PinConglomerate=58|PinLength=30|Location.X=1200|Location.Y=648|Name=69|Designator=C-69|PinPropagationDelay=0.000000E+000
|RECORD=2|OwnerIndex=1045|OwnerPartId=3|FormalType=1|PinConglomerate=56|PinLength=30|Location.X=1260|Location.Y=648|Name=70|Designator=C-70|PinPropagationDelay=0.000000E+000
|RECORD=2|OwnerIndex=1045|OwnerPartId=3|FormalType=1|PinConglomerate=58|PinLength=30|Location.X=1200|Location.Y=638|Name=71|Designator=C-71|PinPropagationDelay=0.000000E+000
|RECORD=2|OwnerIndex=1045|OwnerPartId=3|FormalType=1|PinConglomerate=56|PinLength=30|Location.X=1260|Location.Y=638|Name=72|Designator=C-72|PinPropagationDelay=0.000000E+000
|RECORD=2|OwnerIndex=1045|OwnerPartId=3|FormalType=1|PinConglomerate=58|PinLength=30|Location.X=1200|Location.Y=628|Name=73|Designator=C-73|PinPropagationDelay=0.000000E+000
|RECORD=2|OwnerIndex=1045|OwnerPartId=3|FormalType=1|PinConglomerate=56|PinLength=30|Location.X=1260|Location.Y=628|Name=74|Designator=C-74|PinPropagationDelay=0.000000E+000
|RECORD=2|OwnerIndex=1045|OwnerPartId=3|FormalType=1|PinConglomerate=58|PinLength=30|Location.X=1200|Location.Y=618|Name=75|Designator=C-75|PinPropagationDelay=0.000000E+000
|RECORD=2|OwnerIndex=1045|OwnerPartId=3|FormalType=1|PinConglomerate=56|PinLength=30|Location.X=1260|Location.Y=618|Name=76|Designator=C-76|PinPropagationDelay=0.000000E+000
|RECORD=2|OwnerIndex=1045|OwnerPartId=3|FormalType=1|PinConglomerate=58|PinLength=30|Location.X=1200|Location.Y=608|Name=77|Designator=C-77|PinPropagationDelay=0.000000E+000
|RECORD=2|OwnerIndex=1045|OwnerPartId=3|FormalType=1|PinConglomerate=56|PinLength=30|Location.X=1260|Location.Y=608|Name=78|Designator=C-78|PinPropagationDelay=0.000000E+000
|RECORD=2|OwnerIndex=1045|OwnerPartId=3|FormalType=1|PinConglomerate=58|PinLength=30|Location.X=1200|Location.Y=598|Name=79|Designator=C-79|PinPropagationDelay=0.000000E+000
|RECORD=2|OwnerIndex=1045|OwnerPartId=3|FormalType=1|PinConglomerate=56|PinLength=30|Location.X=1260|Location.Y=598|Name=80|Designator=C-80|PinPropagationDelay=0.000000E+000
|RECORD=2|OwnerIndex=1045|OwnerPartId=3|FormalType=1|PinConglomerate=58|PinLength=30|Location.X=1200|Location.Y=588|Name=81|Designator=C-81|PinPropagationDelay=0.000000E+000
|RECORD=2|OwnerIndex=1045|OwnerPartId=3|FormalType=1|PinConglomerate=56|PinLength=30|Location.X=1260|Location.Y=588|Name=82|Designator=C-82|PinPropagationDelay=0.000000E+000
|RECORD=2|OwnerIndex=1045|OwnerPartId=3|FormalType=1|PinConglomerate=58|PinLength=30|Location.X=1200|Location.Y=578|Name=83|Designator=C-83|PinPropagationDelay=0.000000E+000
|RECORD=2|OwnerIndex=1045|OwnerPartId=3|FormalType=1|PinConglomerate=56|PinLength=30|Location.X=1260|Location.Y=578|Name=84|Designator=C-84|PinPropagationDelay=0.000000E+000
|RECORD=14|OwnerIndex=1045|IsNotAccesible=T|IndexInSheet=170|OwnerPartId=4|Location.X=1200|Location.Y=568|Corner.X=1260|Corner.Y=998|Color=128|AreaColor=11599871|IsSolid=T
|RECORD=2|OwnerIndex=1045|OwnerPartId=4|FormalType=1|PinConglomerate=58|PinLength=30|Location.X=1200|Location.Y=988|Name=1|Designator=D-1|PinPropagationDelay=0.000000E+000
|RECORD=2|OwnerIndex=1045|OwnerPartId=4|FormalType=1|PinConglomerate=56|PinLength=30|Location.X=1260|Location.Y=988|Name=2|Designator=D-2|PinPropagationDelay=0.000000E+000
|RECORD=2|OwnerIndex=1045|OwnerPartId=4|FormalType=1|PinConglomerate=58|PinLength=30|Location.X=1200|Location.Y=978|Name=3|Designator=D-3|PinPropagationDelay=0.000000E+000
|RECORD=2|OwnerIndex=1045|OwnerPartId=4|FormalType=1|PinConglomerate=56|PinLength=30|Location.X=1260|Location.Y=978|Name=4|Designator=D-4|PinPropagationDelay=0.000000E+000
|RECORD=2|OwnerIndex=1045|OwnerPartId=4|FormalType=1|PinConglomerate=58|PinLength=30|Location.X=1200|Location.Y=968|Name=5|Designator=D-5|PinPropagationDelay=0.000000E+000
|RECORD=2|OwnerIndex=1045|OwnerPartId=4|FormalType=1|PinConglomerate=56|PinLength=30|Location.X=1260|Location.Y=968|Name=6|Designator=D-6|PinPropagationDelay=0.000000E+000
|RECORD=2|OwnerIndex=1045|OwnerPartId=4|FormalType=1|PinConglomerate=58|PinLength=30|Location.X=1200|Location.Y=958|Name=7|Designator=D-7|PinPropagationDelay=0.000000E+000
|RECORD=2|OwnerIndex=1045|OwnerPartId=4|FormalType=1|PinConglomerate=56|PinLength=30|Location.X=1260|Location.Y=958|Name=8|Designator=D-8|PinPropagationDelay=0.000000E+000
|RECORD=2|OwnerIndex=1045|OwnerPartId=4|FormalType=1|PinConglomerate=58|PinLength=30|Location.X=1200|Location.Y=948|Name=9|Designator=D-9|PinPropagationDelay=0.000000E+000
|RECORD=2|OwnerIndex=1045|OwnerPartId=4|FormalType=1|PinConglomerate=56|PinLength=30|Location.X=1260|Location.Y=948|Name=10|Designator=D-10|PinPropagationDelay=0.000000E+000
|RECORD=2|OwnerIndex=1045|OwnerPartId=4|FormalType=1|PinConglomerate=58|PinLength=30|Location.X=1200|Location.Y=938|Name=11|Designator=D-11|PinPropagationDelay=0.000000E+000
|RECORD=2|OwnerIndex=1045|OwnerPartId=4|FormalType=1|PinConglomerate=56|PinLength=30|Location.X=1260|Location.Y=938|Name=12|Designator=D-12|PinPropagationDelay=0.000000E+000
|RECORD=2|OwnerIndex=1045|OwnerPartId=4|FormalType=1|PinConglomerate=58|PinLength=30|Location.X=1200|Location.Y=928|Name=13|Designator=D-13|PinPropagationDelay=0.000000E+000
|RECORD=2|OwnerIndex=1045|OwnerPartId=4|FormalType=1|PinConglomerate=56|PinLength=30|Location.X=1260|Location.Y=928|Name=14|Designator=D-14|PinPropagationDelay=0.000000E+000
|RECORD=2|OwnerIndex=1045|OwnerPartId=4|FormalType=1|PinConglomerate=58|PinLength=30|Location.X=1200|Location.Y=918|Name=15|Designator=D-15|PinPropagationDelay=0.000000E+000
|RECORD=2|OwnerIndex=1045|OwnerPartId=4|FormalType=1|PinConglomerate=56|PinLength=30|Location.X=1260|Location.Y=918|Name=16|Designator=D-16|PinPropagationDelay=0.000000E+000
|RECORD=2|OwnerIndex=1045|OwnerPartId=4|FormalType=1|PinConglomerate=58|PinLength=30|Location.X=1200|Location.Y=908|Name=17|Designator=D-17|PinPropagationDelay=0.000000E+000
|RECORD=2|OwnerIndex=1045|OwnerPartId=4|FormalType=1|PinConglomerate=56|PinLength=30|Location.X=1260|Location.Y=908|Name=18|Designator=D-18|PinPropagationDelay=0.000000E+000
|RECORD=2|OwnerIndex=1045|OwnerPartId=4|FormalType=1|PinConglomerate=58|PinLength=30|Location.X=1200|Location.Y=898|Name=19|Designator=D-19|PinPropagationDelay=0.000000E+000
|RECORD=2|OwnerIndex=1045|OwnerPartId=4|FormalType=1|PinConglomerate=56|PinLength=30|Location.X=1260|Location.Y=898|Name=20|Designator=D-20|PinPropagationDelay=0.000000E+000
|RECORD=2|OwnerIndex=1045|OwnerPartId=4|FormalType=1|PinConglomerate=58|PinLength=30|Location.X=1200|Location.Y=888|Name=21|Designator=D-21|PinPropagationDelay=0.000000E+000
|RECORD=2|OwnerIndex=1045|OwnerPartId=4|FormalType=1|PinConglomerate=56|PinLength=30|Location.X=1260|Location.Y=888|Name=22|Designator=D-22|PinPropagationDelay=0.000000E+000
|RECORD=2|OwnerIndex=1045|OwnerPartId=4|FormalType=1|PinConglomerate=58|PinLength=30|Location.X=1200|Location.Y=878|Name=23|Designator=D-23|PinPropagationDelay=0.000000E+000
|RECORD=2|OwnerIndex=1045|OwnerPartId=4|FormalType=1|PinConglomerate=56|PinLength=30|Location.X=1260|Location.Y=878|Name=24|Designator=D-24|PinPropagationDelay=0.000000E+000
|RECORD=2|OwnerIndex=1045|OwnerPartId=4|FormalType=1|PinConglomerate=58|PinLength=30|Location.X=1200|Location.Y=868|Name=25|Designator=D-25|PinPropagationDelay=0.000000E+000
|RECORD=2|OwnerIndex=1045|OwnerPartId=4|FormalType=1|PinConglomerate=56|PinLength=30|Location.X=1260|Location.Y=868|Name=26|Designator=D-26|PinPropagationDelay=0.000000E+000
|RECORD=2|OwnerIndex=1045|OwnerPartId=4|FormalType=1|PinConglomerate=58|PinLength=30|Location.X=1200|Location.Y=858|Name=27|Designator=D-27|PinPropagationDelay=0.000000E+000
|RECORD=2|OwnerIndex=1045|OwnerPartId=4|FormalType=1|PinConglomerate=56|PinLength=30|Location.X=1260|Location.Y=858|Name=28|Designator=D-28|PinPropagationDelay=0.000000E+000
|RECORD=2|OwnerIndex=1045|OwnerPartId=4|FormalType=1|PinConglomerate=58|PinLength=30|Location.X=1200|Location.Y=848|Name=29|Designator=D-29|PinPropagationDelay=0.000000E+000
|RECORD=2|OwnerIndex=1045|OwnerPartId=4|FormalType=1|PinConglomerate=56|PinLength=30|Location.X=1260|Location.Y=848|Name=30|Designator=D-30|PinPropagationDelay=0.000000E+000
|RECORD=2|OwnerIndex=1045|OwnerPartId=4|FormalType=1|PinConglomerate=58|PinLength=30|Location.X=1200|Location.Y=838|Name=31|Designator=D-31|PinPropagationDelay=0.000000E+000
|RECORD=2|OwnerIndex=1045|OwnerPartId=4|FormalType=1|PinConglomerate=56|PinLength=30|Location.X=1260|Location.Y=838|Name=32|Designator=D-32|PinPropagationDelay=0.000000E+000
|RECORD=2|OwnerIndex=1045|OwnerPartId=4|FormalType=1|PinConglomerate=58|PinLength=30|Location.X=1200|Location.Y=828|Name=33|Designator=D-33|PinPropagationDelay=0.000000E+000
|RECORD=2|OwnerIndex=1045|OwnerPartId=4|FormalType=1|PinConglomerate=56|PinLength=30|Location.X=1260|Location.Y=828|Name=34|Designator=D-34|PinPropagationDelay=0.000000E+000
|RECORD=2|OwnerIndex=1045|OwnerPartId=4|FormalType=1|PinConglomerate=58|PinLength=30|Location.X=1200|Location.Y=818|Name=35|Designator=D-35|PinPropagationDelay=0.000000E+000
|RECORD=2|OwnerIndex=1045|OwnerPartId=4|FormalType=1|PinConglomerate=56|PinLength=30|Location.X=1260|Location.Y=818|Name=36|Designator=D-36|PinPropagationDelay=0.000000E+000
|RECORD=2|OwnerIndex=1045|OwnerPartId=4|FormalType=1|PinConglomerate=58|PinLength=30|Location.X=1200|Location.Y=808|Name=37|Designator=D-37|PinPropagationDelay=0.000000E+000
|RECORD=2|OwnerIndex=1045|OwnerPartId=4|FormalType=1|PinConglomerate=56|PinLength=30|Location.X=1260|Location.Y=808|Name=38|Designator=D-38|PinPropagationDelay=0.000000E+000
|RECORD=2|OwnerIndex=1045|OwnerPartId=4|FormalType=1|PinConglomerate=58|PinLength=30|Location.X=1200|Location.Y=798|Name=39|Designator=D-39|PinPropagationDelay=0.000000E+000
|RECORD=2|OwnerIndex=1045|OwnerPartId=4|FormalType=1|PinConglomerate=56|PinLength=30|Location.X=1260|Location.Y=798|Name=40|Designator=D-40|PinPropagationDelay=0.000000E+000
|RECORD=2|OwnerIndex=1045|OwnerPartId=4|FormalType=1|PinConglomerate=58|PinLength=30|Location.X=1200|Location.Y=788|Name=41|Designator=D-41|PinPropagationDelay=0.000000E+000
|RECORD=2|OwnerIndex=1045|OwnerPartId=4|FormalType=1|PinConglomerate=56|PinLength=30|Location.X=1260|Location.Y=788|Name=42|Designator=D-42|PinPropagationDelay=0.000000E+000
|RECORD=2|OwnerIndex=1045|OwnerPartId=4|FormalType=1|PinConglomerate=58|PinLength=30|Location.X=1200|Location.Y=778|Name=43|Designator=D-43|PinPropagationDelay=0.000000E+000
|RECORD=2|OwnerIndex=1045|OwnerPartId=4|FormalType=1|PinConglomerate=56|PinLength=30|Location.X=1260|Location.Y=778|Name=44|Designator=D-44|PinPropagationDelay=0.000000E+000
|RECORD=2|OwnerIndex=1045|OwnerPartId=4|FormalType=1|PinConglomerate=58|PinLength=30|Location.X=1200|Location.Y=768|Name=45|Designator=D-45|PinPropagationDelay=0.000000E+000
|RECORD=2|OwnerIndex=1045|OwnerPartId=4|FormalType=1|PinConglomerate=56|PinLength=30|Location.X=1260|Location.Y=768|Name=46|Designator=D-46|PinPropagationDelay=0.000000E+000
|RECORD=2|OwnerIndex=1045|OwnerPartId=4|FormalType=1|PinConglomerate=58|PinLength=30|Location.X=1200|Location.Y=758|Name=47|Designator=D-47|PinPropagationDelay=0.000000E+000
|RECORD=2|OwnerIndex=1045|OwnerPartId=4|FormalType=1|PinConglomerate=56|PinLength=30|Location.X=1260|Location.Y=758|Name=48|Designator=D-48|PinPropagationDelay=0.000000E+000
|RECORD=2|OwnerIndex=1045|OwnerPartId=4|FormalType=1|PinConglomerate=58|PinLength=30|Location.X=1200|Location.Y=748|Name=49|Designator=D-49|PinPropagationDelay=0.000000E+000
|RECORD=2|OwnerIndex=1045|OwnerPartId=4|FormalType=1|PinConglomerate=56|PinLength=30|Location.X=1260|Location.Y=748|Name=50|Designator=D-50|PinPropagationDelay=0.000000E+000
|RECORD=2|OwnerIndex=1045|OwnerPartId=4|FormalType=1|PinConglomerate=58|PinLength=30|Location.X=1200|Location.Y=738|Name=51|Designator=D-51|PinPropagationDelay=0.000000E+000
|RECORD=2|OwnerIndex=1045|OwnerPartId=4|FormalType=1|PinConglomerate=56|PinLength=30|Location.X=1260|Location.Y=738|Name=52|Designator=D-52|PinPropagationDelay=0.000000E+000
|RECORD=2|OwnerIndex=1045|OwnerPartId=4|FormalType=1|PinConglomerate=58|PinLength=30|Location.X=1200|Location.Y=728|Name=53|Designator=D-53|PinPropagationDelay=0.000000E+000
|RECORD=2|OwnerIndex=1045|OwnerPartId=4|FormalType=1|PinConglomerate=56|PinLength=30|Location.X=1260|Location.Y=728|Name=54|Designator=D-54|PinPropagationDelay=0.000000E+000
|RECORD=2|OwnerIndex=1045|OwnerPartId=4|FormalType=1|PinConglomerate=58|PinLength=30|Location.X=1200|Location.Y=718|Name=55|Designator=D-55|PinPropagationDelay=0.000000E+000
|RECORD=2|OwnerIndex=1045|OwnerPartId=4|FormalType=1|PinConglomerate=56|PinLength=30|Location.X=1260|Location.Y=718|Name=56|Designator=D-56|PinPropagationDelay=0.000000E+000
|RECORD=2|OwnerIndex=1045|OwnerPartId=4|FormalType=1|PinConglomerate=58|PinLength=30|Location.X=1200|Location.Y=708|Name=57|Designator=D-57|PinPropagationDelay=0.000000E+000
|RECORD=2|OwnerIndex=1045|OwnerPartId=4|FormalType=1|PinConglomerate=56|PinLength=30|Location.X=1260|Location.Y=708|Name=58|Designator=D-58|PinPropagationDelay=0.000000E+000
|RECORD=2|OwnerIndex=1045|OwnerPartId=4|FormalType=1|PinConglomerate=58|PinLength=30|Location.X=1200|Location.Y=698|Name=59|Designator=D-59|PinPropagationDelay=0.000000E+000
|RECORD=2|OwnerIndex=1045|OwnerPartId=4|FormalType=1|PinConglomerate=56|PinLength=30|Location.X=1260|Location.Y=698|Name=60|Designator=D-60|PinPropagationDelay=0.000000E+000
|RECORD=2|OwnerIndex=1045|OwnerPartId=4|FormalType=1|PinConglomerate=58|PinLength=30|Location.X=1200|Location.Y=688|Name=61|Designator=D-61|PinPropagationDelay=0.000000E+000
|RECORD=2|OwnerIndex=1045|OwnerPartId=4|FormalType=1|PinConglomerate=56|PinLength=30|Location.X=1260|Location.Y=688|Name=62|Designator=D-62|PinPropagationDelay=0.000000E+000
|RECORD=2|OwnerIndex=1045|OwnerPartId=4|FormalType=1|PinConglomerate=58|PinLength=30|Location.X=1200|Location.Y=678|Name=63|Designator=D-63|PinPropagationDelay=0.000000E+000
|RECORD=2|OwnerIndex=1045|OwnerPartId=4|FormalType=1|PinConglomerate=56|PinLength=30|Location.X=1260|Location.Y=678|Name=64|Designator=D-64|PinPropagationDelay=0.000000E+000
|RECORD=2|OwnerIndex=1045|OwnerPartId=4|FormalType=1|PinConglomerate=58|PinLength=30|Location.X=1200|Location.Y=668|Name=65|Designator=D-65|PinPropagationDelay=0.000000E+000
|RECORD=2|OwnerIndex=1045|OwnerPartId=4|FormalType=1|PinConglomerate=56|PinLength=30|Location.X=1260|Location.Y=668|Name=66|Designator=D-66|PinPropagationDelay=0.000000E+000
|RECORD=2|OwnerIndex=1045|OwnerPartId=4|FormalType=1|PinConglomerate=58|PinLength=30|Location.X=1200|Location.Y=658|Name=67|Designator=D-67|PinPropagationDelay=0.000000E+000
|RECORD=2|OwnerIndex=1045|OwnerPartId=4|FormalType=1|PinConglomerate=56|PinLength=30|Location.X=1260|Location.Y=658|Name=68|Designator=D-68|PinPropagationDelay=0.000000E+000
|RECORD=2|OwnerIndex=1045|OwnerPartId=4|FormalType=1|PinConglomerate=58|PinLength=30|Location.X=1200|Location.Y=648|Name=69|Designator=D-69|PinPropagationDelay=0.000000E+000
|RECORD=2|OwnerIndex=1045|OwnerPartId=4|FormalType=1|PinConglomerate=56|PinLength=30|Location.X=1260|Location.Y=648|Name=70|Designator=D-70|PinPropagationDelay=0.000000E+000
|RECORD=2|OwnerIndex=1045|OwnerPartId=4|FormalType=1|PinConglomerate=58|PinLength=30|Location.X=1200|Location.Y=638|Name=71|Designator=D-71|PinPropagationDelay=0.000000E+000
|RECORD=2|OwnerIndex=1045|OwnerPartId=4|FormalType=1|PinConglomerate=56|PinLength=30|Location.X=1260|Location.Y=638|Name=72|Designator=D-72|PinPropagationDelay=0.000000E+000
|RECORD=2|OwnerIndex=1045|OwnerPartId=4|FormalType=1|PinConglomerate=58|PinLength=30|Location.X=1200|Location.Y=628|Name=73|Designator=D-73|PinPropagationDelay=0.000000E+000
|RECORD=2|OwnerIndex=1045|OwnerPartId=4|FormalType=1|PinConglomerate=56|PinLength=30|Location.X=1260|Location.Y=628|Name=74|Designator=D-74|PinPropagationDelay=0.000000E+000
|RECORD=2|OwnerIndex=1045|OwnerPartId=4|FormalType=1|PinConglomerate=58|PinLength=30|Location.X=1200|Location.Y=618|Name=75|Designator=D-75|PinPropagationDelay=0.000000E+000
|RECORD=2|OwnerIndex=1045|OwnerPartId=4|FormalType=1|PinConglomerate=56|PinLength=30|Location.X=1260|Location.Y=618|Name=76|Designator=D-76|PinPropagationDelay=0.000000E+000
|RECORD=2|OwnerIndex=1045|OwnerPartId=4|FormalType=1|PinConglomerate=58|PinLength=30|Location.X=1200|Location.Y=608|Name=77|Designator=D-77|PinPropagationDelay=0.000000E+000
|RECORD=2|OwnerIndex=1045|OwnerPartId=4|FormalType=1|PinConglomerate=56|PinLength=30|Location.X=1260|Location.Y=608|Name=78|Designator=D-78|PinPropagationDelay=0.000000E+000
|RECORD=2|OwnerIndex=1045|OwnerPartId=4|FormalType=1|PinConglomerate=58|PinLength=30|Location.X=1200|Location.Y=598|Name=79|Designator=D-79|PinPropagationDelay=0.000000E+000
|RECORD=2|OwnerIndex=1045|OwnerPartId=4|FormalType=1|PinConglomerate=56|PinLength=30|Location.X=1260|Location.Y=598|Name=80|Designator=D-80|PinPropagationDelay=0.000000E+000
|RECORD=2|OwnerIndex=1045|OwnerPartId=4|FormalType=1|PinConglomerate=58|PinLength=30|Location.X=1200|Location.Y=588|Name=81|Designator=D-81|PinPropagationDelay=0.000000E+000
|RECORD=2|OwnerIndex=1045|OwnerPartId=4|FormalType=1|PinConglomerate=56|PinLength=30|Location.X=1260|Location.Y=588|Name=82|Designator=D-82|PinPropagationDelay=0.000000E+000
|RECORD=2|OwnerIndex=1045|OwnerPartId=4|FormalType=1|PinConglomerate=58|PinLength=30|Location.X=1200|Location.Y=578|Name=83|Designator=D-83|PinPropagationDelay=0.000000E+000
|RECORD=2|OwnerIndex=1045|OwnerPartId=4|FormalType=1|PinConglomerate=56|PinLength=30|Location.X=1260|Location.Y=578|Name=84|Designator=D-84|PinPropagationDelay=0.000000E+000
|RECORD=14|OwnerIndex=1045|IsNotAccesible=T|IndexInSheet=255|OwnerPartId=1|Location.X=1200|Location.Y=568|Corner.X=1260|Corner.Y=998|Color=128|AreaColor=11599871|IsSolid=T
|RECORD=2|OwnerIndex=1045|OwnerPartId=1|FormalType=1|PinConglomerate=58|PinLength=30|Location.X=1200|Location.Y=988|Name=1|Designator=A-1|PinPropagationDelay=0.000000E+000
|RECORD=2|OwnerIndex=1045|OwnerPartId=1|FormalType=1|PinConglomerate=56|PinLength=30|Location.X=1260|Location.Y=988|Name=2|Designator=A-2|PinPropagationDelay=0.000000E+000
|RECORD=2|OwnerIndex=1045|OwnerPartId=1|FormalType=1|PinConglomerate=58|PinLength=30|Location.X=1200|Location.Y=978|Name=3|Designator=A-3|PinPropagationDelay=0.000000E+000
|RECORD=2|OwnerIndex=1045|OwnerPartId=1|FormalType=1|PinConglomerate=56|PinLength=30|Location.X=1260|Location.Y=978|Name=4|Designator=A-4|PinPropagationDelay=0.000000E+000
|RECORD=2|OwnerIndex=1045|OwnerPartId=1|FormalType=1|PinConglomerate=58|PinLength=30|Location.X=1200|Location.Y=968|Name=5|Designator=A-5|PinPropagationDelay=0.000000E+000
|RECORD=2|OwnerIndex=1045|OwnerPartId=1|FormalType=1|PinConglomerate=56|PinLength=30|Location.X=1260|Location.Y=968|Name=6|Designator=A-6|PinPropagationDelay=0.000000E+000
|RECORD=2|OwnerIndex=1045|OwnerPartId=1|FormalType=1|PinConglomerate=58|PinLength=30|Location.X=1200|Location.Y=958|Name=7|Designator=A-7|PinPropagationDelay=0.000000E+000
|RECORD=2|OwnerIndex=1045|OwnerPartId=1|FormalType=1|PinConglomerate=56|PinLength=30|Location.X=1260|Location.Y=958|Name=8|Designator=A-8|PinPropagationDelay=0.000000E+000
|RECORD=2|OwnerIndex=1045|OwnerPartId=1|FormalType=1|PinConglomerate=58|PinLength=30|Location.X=1200|Location.Y=948|Name=9|Designator=A-9|PinPropagationDelay=0.000000E+000
|RECORD=2|OwnerIndex=1045|OwnerPartId=1|FormalType=1|PinConglomerate=56|PinLength=30|Location.X=1260|Location.Y=948|Name=10|Designator=A-10|PinPropagationDelay=0.000000E+000
|RECORD=2|OwnerIndex=1045|OwnerPartId=1|FormalType=1|PinConglomerate=58|PinLength=30|Location.X=1200|Location.Y=938|Name=11|Designator=A-11|PinPropagationDelay=0.000000E+000
|RECORD=2|OwnerIndex=1045|OwnerPartId=1|FormalType=1|PinConglomerate=56|PinLength=30|Location.X=1260|Location.Y=938|Name=12|Designator=A-12|PinPropagationDelay=0.000000E+000
|RECORD=2|OwnerIndex=1045|OwnerPartId=1|FormalType=1|PinConglomerate=58|PinLength=30|Location.X=1200|Location.Y=928|Name=13|Designator=A-13|PinPropagationDelay=0.000000E+000
|RECORD=2|OwnerIndex=1045|OwnerPartId=1|FormalType=1|PinConglomerate=56|PinLength=30|Location.X=1260|Location.Y=928|Name=14|Designator=A-14|PinPropagationDelay=0.000000E+000
|RECORD=2|OwnerIndex=1045|OwnerPartId=1|FormalType=1|PinConglomerate=58|PinLength=30|Location.X=1200|Location.Y=918|Name=15|Designator=A-15|PinPropagationDelay=0.000000E+000
|RECORD=2|OwnerIndex=1045|OwnerPartId=1|FormalType=1|PinConglomerate=56|PinLength=30|Location.X=1260|Location.Y=918|Name=16|Designator=A-16|PinPropagationDelay=0.000000E+000
|RECORD=2|OwnerIndex=1045|OwnerPartId=1|FormalType=1|PinConglomerate=58|PinLength=30|Location.X=1200|Location.Y=908|Name=17|Designator=A-17|PinPropagationDelay=0.000000E+000
|RECORD=2|OwnerIndex=1045|OwnerPartId=1|FormalType=1|PinConglomerate=56|PinLength=30|Location.X=1260|Location.Y=908|Name=18|Designator=A-18|PinPropagationDelay=0.000000E+000
|RECORD=2|OwnerIndex=1045|OwnerPartId=1|FormalType=1|PinConglomerate=58|PinLength=30|Location.X=1200|Location.Y=898|Name=19|Designator=A-19|PinPropagationDelay=0.000000E+000
|RECORD=2|OwnerIndex=1045|OwnerPartId=1|FormalType=1|PinConglomerate=56|PinLength=30|Location.X=1260|Location.Y=898|Name=20|Designator=A-20|PinPropagationDelay=0.000000E+000
|RECORD=2|OwnerIndex=1045|OwnerPartId=1|FormalType=1|PinConglomerate=58|PinLength=30|Location.X=1200|Location.Y=888|Name=21|Designator=A-21|PinPropagationDelay=0.000000E+000
|RECORD=2|OwnerIndex=1045|OwnerPartId=1|FormalType=1|PinConglomerate=56|PinLength=30|Location.X=1260|Location.Y=888|Name=22|Designator=A-22|PinPropagationDelay=0.000000E+000
|RECORD=2|OwnerIndex=1045|OwnerPartId=1|FormalType=1|PinConglomerate=58|PinLength=30|Location.X=1200|Location.Y=878|Name=23|Designator=A-23|PinPropagationDelay=0.000000E+000
|RECORD=2|OwnerIndex=1045|OwnerPartId=1|FormalType=1|PinConglomerate=56|PinLength=30|Location.X=1260|Location.Y=878|Name=24|Designator=A-24|PinPropagationDelay=0.000000E+000
|RECORD=2|OwnerIndex=1045|OwnerPartId=1|FormalType=1|PinConglomerate=58|PinLength=30|Location.X=1200|Location.Y=868|Name=25|Designator=A-25|PinPropagationDelay=0.000000E+000
|RECORD=2|OwnerIndex=1045|OwnerPartId=1|FormalType=1|PinConglomerate=56|PinLength=30|Location.X=1260|Location.Y=868|Name=26|Designator=A-26|PinPropagationDelay=0.000000E+000
|RECORD=2|OwnerIndex=1045|OwnerPartId=1|FormalType=1|PinConglomerate=58|PinLength=30|Location.X=1200|Location.Y=858|Name=27|Designator=A-27|PinPropagationDelay=0.000000E+000
|RECORD=2|OwnerIndex=1045|OwnerPartId=1|FormalType=1|PinConglomerate=56|PinLength=30|Location.X=1260|Location.Y=858|Name=28|Designator=A-28|PinPropagationDelay=0.000000E+000
|RECORD=2|OwnerIndex=1045|OwnerPartId=1|FormalType=1|PinConglomerate=58|PinLength=30|Location.X=1200|Location.Y=848|Name=29|Designator=A-29|PinPropagationDelay=0.000000E+000
|RECORD=2|OwnerIndex=1045|OwnerPartId=1|FormalType=1|PinConglomerate=56|PinLength=30|Location.X=1260|Location.Y=848|Name=30|Designator=A-30|PinPropagationDelay=0.000000E+000
|RECORD=2|OwnerIndex=1045|OwnerPartId=1|FormalType=1|PinConglomerate=58|PinLength=30|Location.X=1200|Location.Y=838|Name=31|Designator=A-31|PinPropagationDelay=0.000000E+000
|RECORD=2|OwnerIndex=1045|OwnerPartId=1|FormalType=1|PinConglomerate=56|PinLength=30|Location.X=1260|Location.Y=838|Name=32|Designator=A-32|PinPropagationDelay=0.000000E+000
|RECORD=2|OwnerIndex=1045|OwnerPartId=1|FormalType=1|PinConglomerate=58|PinLength=30|Location.X=1200|Location.Y=828|Name=33|Designator=A-33|PinPropagationDelay=0.000000E+000
|RECORD=2|OwnerIndex=1045|OwnerPartId=1|FormalType=1|PinConglomerate=56|PinLength=30|Location.X=1260|Location.Y=828|Name=34|Designator=A-34|PinPropagationDelay=0.000000E+000
|RECORD=2|OwnerIndex=1045|OwnerPartId=1|FormalType=1|PinConglomerate=58|PinLength=30|Location.X=1200|Location.Y=818|Name=35|Designator=A-35|PinPropagationDelay=0.000000E+000
|RECORD=2|OwnerIndex=1045|OwnerPartId=1|FormalType=1|PinConglomerate=56|PinLength=30|Location.X=1260|Location.Y=818|Name=36|Designator=A-36|PinPropagationDelay=0.000000E+000
|RECORD=2|OwnerIndex=1045|OwnerPartId=1|FormalType=1|PinConglomerate=58|PinLength=30|Location.X=1200|Location.Y=808|Name=37|Designator=A-37|PinPropagationDelay=0.000000E+000
|RECORD=2|OwnerIndex=1045|OwnerPartId=1|FormalType=1|PinConglomerate=56|PinLength=30|Location.X=1260|Location.Y=808|Name=38|Designator=A-38|PinPropagationDelay=0.000000E+000
|RECORD=2|OwnerIndex=1045|OwnerPartId=1|FormalType=1|PinConglomerate=58|PinLength=30|Location.X=1200|Location.Y=798|Name=39|Designator=A-39|PinPropagationDelay=0.000000E+000
|RECORD=2|OwnerIndex=1045|OwnerPartId=1|FormalType=1|PinConglomerate=56|PinLength=30|Location.X=1260|Location.Y=798|Name=40|Designator=A-40|PinPropagationDelay=0.000000E+000
|RECORD=2|OwnerIndex=1045|OwnerPartId=1|FormalType=1|PinConglomerate=58|PinLength=30|Location.X=1200|Location.Y=788|Name=41|Designator=A-41|PinPropagationDelay=0.000000E+000
|RECORD=2|OwnerIndex=1045|OwnerPartId=1|FormalType=1|PinConglomerate=56|PinLength=30|Location.X=1260|Location.Y=788|Name=42|Designator=A-42|PinPropagationDelay=0.000000E+000
|RECORD=2|OwnerIndex=1045|OwnerPartId=1|FormalType=1|PinConglomerate=58|PinLength=30|Location.X=1200|Location.Y=778|Name=43|Designator=A-43|PinPropagationDelay=0.000000E+000
|RECORD=2|OwnerIndex=1045|OwnerPartId=1|FormalType=1|PinConglomerate=56|PinLength=30|Location.X=1260|Location.Y=778|Name=44|Designator=A-44|PinPropagationDelay=0.000000E+000
|RECORD=2|OwnerIndex=1045|OwnerPartId=1|FormalType=1|PinConglomerate=58|PinLength=30|Location.X=1200|Location.Y=768|Name=45|Designator=A-45|PinPropagationDelay=0.000000E+000
|RECORD=2|OwnerIndex=1045|OwnerPartId=1|FormalType=1|PinConglomerate=56|PinLength=30|Location.X=1260|Location.Y=768|Name=46|Designator=A-46|PinPropagationDelay=0.000000E+000
|RECORD=2|OwnerIndex=1045|OwnerPartId=1|FormalType=1|PinConglomerate=58|PinLength=30|Location.X=1200|Location.Y=758|Name=47|Designator=A-47|PinPropagationDelay=0.000000E+000
|RECORD=2|OwnerIndex=1045|OwnerPartId=1|FormalType=1|PinConglomerate=56|PinLength=30|Location.X=1260|Location.Y=758|Name=48|Designator=A-48|PinPropagationDelay=0.000000E+000
|RECORD=2|OwnerIndex=1045|OwnerPartId=1|FormalType=1|PinConglomerate=58|PinLength=30|Location.X=1200|Location.Y=748|Name=49|Designator=A-49|PinPropagationDelay=0.000000E+000
|RECORD=2|OwnerIndex=1045|OwnerPartId=1|FormalType=1|PinConglomerate=56|PinLength=30|Location.X=1260|Location.Y=748|Name=50|Designator=A-50|PinPropagationDelay=0.000000E+000
|RECORD=2|OwnerIndex=1045|OwnerPartId=1|FormalType=1|PinConglomerate=58|PinLength=30|Location.X=1200|Location.Y=738|Name=51|Designator=A-51|PinPropagationDelay=0.000000E+000
|RECORD=2|OwnerIndex=1045|OwnerPartId=1|FormalType=1|PinConglomerate=56|PinLength=30|Location.X=1260|Location.Y=738|Name=52|Designator=A-52|PinPropagationDelay=0.000000E+000
|RECORD=2|OwnerIndex=1045|OwnerPartId=1|FormalType=1|PinConglomerate=58|PinLength=30|Location.X=1200|Location.Y=728|Name=53|Designator=A-53|PinPropagationDelay=0.000000E+000
|RECORD=2|OwnerIndex=1045|OwnerPartId=1|FormalType=1|PinConglomerate=56|PinLength=30|Location.X=1260|Location.Y=728|Name=54|Designator=A-54|PinPropagationDelay=0.000000E+000
|RECORD=2|OwnerIndex=1045|OwnerPartId=1|FormalType=1|PinConglomerate=58|PinLength=30|Location.X=1200|Location.Y=718|Name=55|Designator=A-55|PinPropagationDelay=0.000000E+000
|RECORD=2|OwnerIndex=1045|OwnerPartId=1|FormalType=1|PinConglomerate=56|PinLength=30|Location.X=1260|Location.Y=718|Name=56|Designator=A-56|PinPropagationDelay=0.000000E+000
|RECORD=2|OwnerIndex=1045|OwnerPartId=1|FormalType=1|PinConglomerate=58|PinLength=30|Location.X=1200|Location.Y=708|Name=57|Designator=A-57|PinPropagationDelay=0.000000E+000
|RECORD=2|OwnerIndex=1045|OwnerPartId=1|FormalType=1|PinConglomerate=56|PinLength=30|Location.X=1260|Location.Y=708|Name=58|Designator=A-58|PinPropagationDelay=0.000000E+000
|RECORD=2|OwnerIndex=1045|OwnerPartId=1|FormalType=1|PinConglomerate=58|PinLength=30|Location.X=1200|Location.Y=698|Name=59|Designator=A-59|PinPropagationDelay=0.000000E+000
|RECORD=2|OwnerIndex=1045|OwnerPartId=1|FormalType=1|PinConglomerate=56|PinLength=30|Location.X=1260|Location.Y=698|Name=60|Designator=A-60|PinPropagationDelay=0.000000E+000
|RECORD=2|OwnerIndex=1045|OwnerPartId=1|FormalType=1|PinConglomerate=58|PinLength=30|Location.X=1200|Location.Y=688|Name=61|Designator=A-61|PinPropagationDelay=0.000000E+000
|RECORD=2|OwnerIndex=1045|OwnerPartId=1|FormalType=1|PinConglomerate=56|PinLength=30|Location.X=1260|Location.Y=688|Name=62|Designator=A-62|PinPropagationDelay=0.000000E+000
|RECORD=2|OwnerIndex=1045|OwnerPartId=1|FormalType=1|PinConglomerate=58|PinLength=30|Location.X=1200|Location.Y=678|Name=63|Designator=A-63|PinPropagationDelay=0.000000E+000
|RECORD=2|OwnerIndex=1045|OwnerPartId=1|FormalType=1|PinConglomerate=56|PinLength=30|Location.X=1260|Location.Y=678|Name=64|Designator=A-64|PinPropagationDelay=0.000000E+000
|RECORD=2|OwnerIndex=1045|OwnerPartId=1|FormalType=1|PinConglomerate=58|PinLength=30|Location.X=1200|Location.Y=668|Name=65|Designator=A-65|PinPropagationDelay=0.000000E+000
|RECORD=2|OwnerIndex=1045|OwnerPartId=1|FormalType=1|PinConglomerate=56|PinLength=30|Location.X=1260|Location.Y=668|Name=66|Designator=A-66|PinPropagationDelay=0.000000E+000
|RECORD=2|OwnerIndex=1045|OwnerPartId=1|FormalType=1|PinConglomerate=58|PinLength=30|Location.X=1200|Location.Y=658|Name=67|Designator=A-67|PinPropagationDelay=0.000000E+000
|RECORD=2|OwnerIndex=1045|OwnerPartId=1|FormalType=1|PinConglomerate=56|PinLength=30|Location.X=1260|Location.Y=658|Name=68|Designator=A-68|PinPropagationDelay=0.000000E+000
|RECORD=2|OwnerIndex=1045|OwnerPartId=1|FormalType=1|PinConglomerate=58|PinLength=30|Location.X=1200|Location.Y=648|Name=69|Designator=A-69|PinPropagationDelay=0.000000E+000
|RECORD=2|OwnerIndex=1045|OwnerPartId=1|FormalType=1|PinConglomerate=56|PinLength=30|Location.X=1260|Location.Y=648|Name=70|Designator=A-70|PinPropagationDelay=0.000000E+000
|RECORD=2|OwnerIndex=1045|OwnerPartId=1|FormalType=1|PinConglomerate=58|PinLength=30|Location.X=1200|Location.Y=638|Name=71|Designator=A-71|PinPropagationDelay=0.000000E+000
|RECORD=2|OwnerIndex=1045|OwnerPartId=1|FormalType=1|PinConglomerate=56|PinLength=30|Location.X=1260|Location.Y=638|Name=72|Designator=A-72|PinPropagationDelay=0.000000E+000
|RECORD=2|OwnerIndex=1045|OwnerPartId=1|FormalType=1|PinConglomerate=58|PinLength=30|Location.X=1200|Location.Y=628|Name=73|Designator=A-73|PinPropagationDelay=0.000000E+000
|RECORD=2|OwnerIndex=1045|OwnerPartId=1|FormalType=1|PinConglomerate=56|PinLength=30|Location.X=1260|Location.Y=628|Name=74|Designator=A-74|PinPropagationDelay=0.000000E+000
|RECORD=2|OwnerIndex=1045|OwnerPartId=1|FormalType=1|PinConglomerate=58|PinLength=30|Location.X=1200|Location.Y=618|Name=75|Designator=A-75|PinPropagationDelay=0.000000E+000
|RECORD=2|OwnerIndex=1045|OwnerPartId=1|FormalType=1|PinConglomerate=56|PinLength=30|Location.X=1260|Location.Y=618|Name=76|Designator=A-76|PinPropagationDelay=0.000000E+000
|RECORD=2|OwnerIndex=1045|OwnerPartId=1|FormalType=1|PinConglomerate=58|PinLength=30|Location.X=1200|Location.Y=608|Name=77|Designator=A-77|PinPropagationDelay=0.000000E+000
|RECORD=2|OwnerIndex=1045|OwnerPartId=1|FormalType=1|PinConglomerate=56|PinLength=30|Location.X=1260|Location.Y=608|Name=78|Designator=A-78|PinPropagationDelay=0.000000E+000
|RECORD=2|OwnerIndex=1045|OwnerPartId=1|FormalType=1|PinConglomerate=58|PinLength=30|Location.X=1200|Location.Y=598|Name=79|Designator=A-79|PinPropagationDelay=0.000000E+000
|RECORD=2|OwnerIndex=1045|OwnerPartId=1|FormalType=1|PinConglomerate=56|PinLength=30|Location.X=1260|Location.Y=598|Name=80|Designator=A-80|PinPropagationDelay=0.000000E+000
|RECORD=2|OwnerIndex=1045|OwnerPartId=1|FormalType=1|PinConglomerate=58|PinLength=30|Location.X=1200|Location.Y=588|Name=81|Designator=A-81|PinPropagationDelay=0.000000E+000
|RECORD=2|OwnerIndex=1045|OwnerPartId=1|FormalType=1|PinConglomerate=56|PinLength=30|Location.X=1260|Location.Y=588|Name=82|Designator=A-82|PinPropagationDelay=0.000000E+000
|RECORD=2|OwnerIndex=1045|OwnerPartId=1|FormalType=1|PinConglomerate=58|PinLength=30|Location.X=1200|Location.Y=578|Name=83|Designator=A-83|PinPropagationDelay=0.000000E+000
|RECORD=2|OwnerIndex=1045|OwnerPartId=1|FormalType=1|PinConglomerate=56|PinLength=30|Location.X=1260|Location.Y=578|Name=84|Designator=A-84|PinPropagationDelay=0.000000E+000
|RECORD=34|OwnerIndex=1045|IndexInSheet=-1|OwnerPartId=-1|Location.X=1200|Location.Y=998|Color=8388608|FontID=1|Text=P1|Name=Designator|ReadOnlyState=1
|RECORD=41|OwnerIndex=1045|IndexInSheet=-1|OwnerPartId=-1|Location.X=1200|Location.Y=558|Color=8388608|FontID=1|Text=FPGA_CONN|Name=Comment
|RECORD=44|OwnerIndex=1045
|RECORD=45|OwnerIndex=1724|IndexInSheet=-1|ModelName=FPGA_CONN|ModelType=PCBLIB|DatafileCount=1|ModelDatafileEntity0=FPGA_CONN|ModelDatafileKind0=PCBLib|IsCurrent=T
|RECORD=46|OwnerIndex=1725
|RECORD=48|OwnerIndex=1725
|RECORD=1|LibReference=FPGA_CONN|PartCount=5|DisplayModeCount=1|IndexInSheet=335|OwnerPartId=-1|Location.X=460|Location.Y=498|CurrentPartId=3|LibraryPath=*|SourceLibraryName=FPGA_CONN.SchLib|TargetFileName=*|AreaColor=11599871|Color=128|PartIDLocked=T|NotUseDBTableName=T|DesignItemId=FPGA_CONN|AllPinCount=336
|RECORD=14|OwnerIndex=1728|IsNotAccesible=T|OwnerPartId=2|Location.X=490|Location.Y=78|Corner.X=550|Corner.Y=508|Color=128|AreaColor=11599871|IsSolid=T
|RECORD=2|OwnerIndex=1728|OwnerPartId=2|FormalType=1|PinConglomerate=58|PinLength=30|Location.X=490|Location.Y=498|Name=1|Designator=B-1|PinPropagationDelay=0.000000E+000
|RECORD=2|OwnerIndex=1728|OwnerPartId=2|FormalType=1|PinConglomerate=56|PinLength=30|Location.X=550|Location.Y=498|Name=2|Designator=B-2|PinPropagationDelay=0.000000E+000
|RECORD=2|OwnerIndex=1728|OwnerPartId=2|FormalType=1|PinConglomerate=58|PinLength=30|Location.X=490|Location.Y=488|Name=3|Designator=B-3|PinPropagationDelay=0.000000E+000
|RECORD=2|OwnerIndex=1728|OwnerPartId=2|FormalType=1|PinConglomerate=56|PinLength=30|Location.X=550|Location.Y=488|Name=4|Designator=B-4|PinPropagationDelay=0.000000E+000
|RECORD=2|OwnerIndex=1728|OwnerPartId=2|FormalType=1|PinConglomerate=58|PinLength=30|Location.X=490|Location.Y=478|Name=5|Designator=B-5|PinPropagationDelay=0.000000E+000
|RECORD=2|OwnerIndex=1728|OwnerPartId=2|FormalType=1|PinConglomerate=56|PinLength=30|Location.X=550|Location.Y=478|Name=6|Designator=B-6|PinPropagationDelay=0.000000E+000
|RECORD=2|OwnerIndex=1728|OwnerPartId=2|FormalType=1|PinConglomerate=58|PinLength=30|Location.X=490|Location.Y=468|Name=7|Designator=B-7|PinPropagationDelay=0.000000E+000
|RECORD=2|OwnerIndex=1728|OwnerPartId=2|FormalType=1|PinConglomerate=56|PinLength=30|Location.X=550|Location.Y=468|Name=8|Designator=B-8|PinPropagationDelay=0.000000E+000
|RECORD=2|OwnerIndex=1728|OwnerPartId=2|FormalType=1|PinConglomerate=58|PinLength=30|Location.X=490|Location.Y=458|Name=9|Designator=B-9|PinPropagationDelay=0.000000E+000
|RECORD=2|OwnerIndex=1728|OwnerPartId=2|FormalType=1|PinConglomerate=56|PinLength=30|Location.X=550|Location.Y=458|Name=10|Designator=B-10|PinPropagationDelay=0.000000E+000
|RECORD=2|OwnerIndex=1728|OwnerPartId=2|FormalType=1|PinConglomerate=58|PinLength=30|Location.X=490|Location.Y=448|Name=11|Designator=B-11|PinPropagationDelay=0.000000E+000
|RECORD=2|OwnerIndex=1728|OwnerPartId=2|FormalType=1|PinConglomerate=56|PinLength=30|Location.X=550|Location.Y=448|Name=12|Designator=B-12|PinPropagationDelay=0.000000E+000
|RECORD=2|OwnerIndex=1728|OwnerPartId=2|FormalType=1|PinConglomerate=58|PinLength=30|Location.X=490|Location.Y=438|Name=13|Designator=B-13|PinPropagationDelay=0.000000E+000
|RECORD=2|OwnerIndex=1728|OwnerPartId=2|FormalType=1|PinConglomerate=56|PinLength=30|Location.X=550|Location.Y=438|Name=14|Designator=B-14|PinPropagationDelay=0.000000E+000
|RECORD=2|OwnerIndex=1728|OwnerPartId=2|FormalType=1|PinConglomerate=58|PinLength=30|Location.X=490|Location.Y=428|Name=15|Designator=B-15|PinPropagationDelay=0.000000E+000
|RECORD=2|OwnerIndex=1728|OwnerPartId=2|FormalType=1|PinConglomerate=56|PinLength=30|Location.X=550|Location.Y=428|Name=16|Designator=B-16|PinPropagationDelay=0.000000E+000
|RECORD=2|OwnerIndex=1728|OwnerPartId=2|FormalType=1|PinConglomerate=58|PinLength=30|Location.X=490|Location.Y=418|Name=17|Designator=B-17|PinPropagationDelay=0.000000E+000
|RECORD=2|OwnerIndex=1728|OwnerPartId=2|FormalType=1|PinConglomerate=56|PinLength=30|Location.X=550|Location.Y=418|Name=18|Designator=B-18|PinPropagationDelay=0.000000E+000
|RECORD=2|OwnerIndex=1728|OwnerPartId=2|FormalType=1|PinConglomerate=58|PinLength=30|Location.X=490|Location.Y=408|Name=19|Designator=B-19|PinPropagationDelay=0.000000E+000
|RECORD=2|OwnerIndex=1728|OwnerPartId=2|FormalType=1|PinConglomerate=56|PinLength=30|Location.X=550|Location.Y=408|Name=20|Designator=B-20|PinPropagationDelay=0.000000E+000
|RECORD=2|OwnerIndex=1728|OwnerPartId=2|FormalType=1|PinConglomerate=58|PinLength=30|Location.X=490|Location.Y=398|Name=21|Designator=B-21|PinPropagationDelay=0.000000E+000
|RECORD=2|OwnerIndex=1728|OwnerPartId=2|FormalType=1|PinConglomerate=56|PinLength=30|Location.X=550|Location.Y=398|Name=22|Designator=B-22|PinPropagationDelay=0.000000E+000
|RECORD=2|OwnerIndex=1728|OwnerPartId=2|FormalType=1|PinConglomerate=58|PinLength=30|Location.X=490|Location.Y=388|Name=23|Designator=B-23|PinPropagationDelay=0.000000E+000
|RECORD=2|OwnerIndex=1728|OwnerPartId=2|FormalType=1|PinConglomerate=56|PinLength=30|Location.X=550|Location.Y=388|Name=24|Designator=B-24|PinPropagationDelay=0.000000E+000
|RECORD=2|OwnerIndex=1728|OwnerPartId=2|FormalType=1|PinConglomerate=58|PinLength=30|Location.X=490|Location.Y=378|Name=25|Designator=B-25|PinPropagationDelay=0.000000E+000
|RECORD=2|OwnerIndex=1728|OwnerPartId=2|FormalType=1|PinConglomerate=56|PinLength=30|Location.X=550|Location.Y=378|Name=26|Designator=B-26|PinPropagationDelay=0.000000E+000
|RECORD=2|OwnerIndex=1728|OwnerPartId=2|FormalType=1|PinConglomerate=58|PinLength=30|Location.X=490|Location.Y=368|Name=27|Designator=B-27|PinPropagationDelay=0.000000E+000
|RECORD=2|OwnerIndex=1728|OwnerPartId=2|FormalType=1|PinConglomerate=56|PinLength=30|Location.X=550|Location.Y=368|Name=28|Designator=B-28|PinPropagationDelay=0.000000E+000
|RECORD=2|OwnerIndex=1728|OwnerPartId=2|FormalType=1|PinConglomerate=58|PinLength=30|Location.X=490|Location.Y=358|Name=29|Designator=B-29|PinPropagationDelay=0.000000E+000
|RECORD=2|OwnerIndex=1728|OwnerPartId=2|FormalType=1|PinConglomerate=56|PinLength=30|Location.X=550|Location.Y=358|Name=30|Designator=B-30|PinPropagationDelay=0.000000E+000
|RECORD=2|OwnerIndex=1728|OwnerPartId=2|FormalType=1|PinConglomerate=58|PinLength=30|Location.X=490|Location.Y=348|Name=31|Designator=B-31|PinPropagationDelay=0.000000E+000
|RECORD=2|OwnerIndex=1728|OwnerPartId=2|FormalType=1|PinConglomerate=56|PinLength=30|Location.X=550|Location.Y=348|Name=32|Designator=B-32|PinPropagationDelay=0.000000E+000
|RECORD=2|OwnerIndex=1728|OwnerPartId=2|FormalType=1|PinConglomerate=58|PinLength=30|Location.X=490|Location.Y=338|Name=33|Designator=B-33|PinPropagationDelay=0.000000E+000
|RECORD=2|OwnerIndex=1728|OwnerPartId=2|FormalType=1|PinConglomerate=56|PinLength=30|Location.X=550|Location.Y=338|Name=34|Designator=B-34|PinPropagationDelay=0.000000E+000
|RECORD=2|OwnerIndex=1728|OwnerPartId=2|FormalType=1|PinConglomerate=58|PinLength=30|Location.X=490|Location.Y=328|Name=35|Designator=B-35|PinPropagationDelay=0.000000E+000
|RECORD=2|OwnerIndex=1728|OwnerPartId=2|FormalType=1|PinConglomerate=56|PinLength=30|Location.X=550|Location.Y=328|Name=36|Designator=B-36|PinPropagationDelay=0.000000E+000
|RECORD=2|OwnerIndex=1728|OwnerPartId=2|FormalType=1|PinConglomerate=58|PinLength=30|Location.X=490|Location.Y=318|Name=37|Designator=B-37|PinPropagationDelay=0.000000E+000
|RECORD=2|OwnerIndex=1728|OwnerPartId=2|FormalType=1|PinConglomerate=56|PinLength=30|Location.X=550|Location.Y=318|Name=38|Designator=B-38|PinPropagationDelay=0.000000E+000
|RECORD=2|OwnerIndex=1728|OwnerPartId=2|FormalType=1|PinConglomerate=58|PinLength=30|Location.X=490|Location.Y=308|Name=39|Designator=B-39|PinPropagationDelay=0.000000E+000
|RECORD=2|OwnerIndex=1728|OwnerPartId=2|FormalType=1|PinConglomerate=56|PinLength=30|Location.X=550|Location.Y=308|Name=40|Designator=B-40|PinPropagationDelay=0.000000E+000
|RECORD=2|OwnerIndex=1728|OwnerPartId=2|FormalType=1|PinConglomerate=58|PinLength=30|Location.X=490|Location.Y=298|Name=41|Designator=B-41|PinPropagationDelay=0.000000E+000
|RECORD=2|OwnerIndex=1728|OwnerPartId=2|FormalType=1|PinConglomerate=56|PinLength=30|Location.X=550|Location.Y=298|Name=42|Designator=B-42|PinPropagationDelay=0.000000E+000
|RECORD=2|OwnerIndex=1728|OwnerPartId=2|FormalType=1|PinConglomerate=58|PinLength=30|Location.X=490|Location.Y=288|Name=43|Designator=B-43|PinPropagationDelay=0.000000E+000
|RECORD=2|OwnerIndex=1728|OwnerPartId=2|FormalType=1|PinConglomerate=56|PinLength=30|Location.X=550|Location.Y=288|Name=44|Designator=B-44|PinPropagationDelay=0.000000E+000
|RECORD=2|OwnerIndex=1728|OwnerPartId=2|FormalType=1|PinConglomerate=58|PinLength=30|Location.X=490|Location.Y=278|Name=45|Designator=B-45|PinPropagationDelay=0.000000E+000
|RECORD=2|OwnerIndex=1728|OwnerPartId=2|FormalType=1|PinConglomerate=56|PinLength=30|Location.X=550|Location.Y=278|Name=46|Designator=B-46|PinPropagationDelay=0.000000E+000
|RECORD=2|OwnerIndex=1728|OwnerPartId=2|FormalType=1|PinConglomerate=58|PinLength=30|Location.X=490|Location.Y=268|Name=47|Designator=B-47|PinPropagationDelay=0.000000E+000
|RECORD=2|OwnerIndex=1728|OwnerPartId=2|FormalType=1|PinConglomerate=56|PinLength=30|Location.X=550|Location.Y=268|Name=48|Designator=B-48|PinPropagationDelay=0.000000E+000
|RECORD=2|OwnerIndex=1728|OwnerPartId=2|FormalType=1|PinConglomerate=58|PinLength=30|Location.X=490|Location.Y=258|Name=49|Designator=B-49|PinPropagationDelay=0.000000E+000
|RECORD=2|OwnerIndex=1728|OwnerPartId=2|FormalType=1|PinConglomerate=56|PinLength=30|Location.X=550|Location.Y=258|Name=50|Designator=B-50|PinPropagationDelay=0.000000E+000
|RECORD=2|OwnerIndex=1728|OwnerPartId=2|FormalType=1|PinConglomerate=58|PinLength=30|Location.X=490|Location.Y=248|Name=51|Designator=B-51|PinPropagationDelay=0.000000E+000
|RECORD=2|OwnerIndex=1728|OwnerPartId=2|FormalType=1|PinConglomerate=56|PinLength=30|Location.X=550|Location.Y=248|Name=52|Designator=B-52|PinPropagationDelay=0.000000E+000
|RECORD=2|OwnerIndex=1728|OwnerPartId=2|FormalType=1|PinConglomerate=58|PinLength=30|Location.X=490|Location.Y=238|Name=53|Designator=B-53|PinPropagationDelay=0.000000E+000
|RECORD=2|OwnerIndex=1728|OwnerPartId=2|FormalType=1|PinConglomerate=56|PinLength=30|Location.X=550|Location.Y=238|Name=54|Designator=B-54|PinPropagationDelay=0.000000E+000
|RECORD=2|OwnerIndex=1728|OwnerPartId=2|FormalType=1|PinConglomerate=58|PinLength=30|Location.X=490|Location.Y=228|Name=55|Designator=B-55|PinPropagationDelay=0.000000E+000
|RECORD=2|OwnerIndex=1728|OwnerPartId=2|FormalType=1|PinConglomerate=56|PinLength=30|Location.X=550|Location.Y=228|Name=56|Designator=B-56|PinPropagationDelay=0.000000E+000
|RECORD=2|OwnerIndex=1728|OwnerPartId=2|FormalType=1|PinConglomerate=58|PinLength=30|Location.X=490|Location.Y=218|Name=57|Designator=B-57|PinPropagationDelay=0.000000E+000
|RECORD=2|OwnerIndex=1728|OwnerPartId=2|FormalType=1|PinConglomerate=56|PinLength=30|Location.X=550|Location.Y=218|Name=58|Designator=B-58|PinPropagationDelay=0.000000E+000
|RECORD=2|OwnerIndex=1728|OwnerPartId=2|FormalType=1|PinConglomerate=58|PinLength=30|Location.X=490|Location.Y=208|Name=59|Designator=B-59|PinPropagationDelay=0.000000E+000
|RECORD=2|OwnerIndex=1728|OwnerPartId=2|FormalType=1|PinConglomerate=56|PinLength=30|Location.X=550|Location.Y=208|Name=60|Designator=B-60|PinPropagationDelay=0.000000E+000
|RECORD=2|OwnerIndex=1728|OwnerPartId=2|FormalType=1|PinConglomerate=58|PinLength=30|Location.X=490|Location.Y=198|Name=61|Designator=B-61|PinPropagationDelay=0.000000E+000
|RECORD=2|OwnerIndex=1728|OwnerPartId=2|FormalType=1|PinConglomerate=56|PinLength=30|Location.X=550|Location.Y=198|Name=62|Designator=B-62|PinPropagationDelay=0.000000E+000
|RECORD=2|OwnerIndex=1728|OwnerPartId=2|FormalType=1|PinConglomerate=58|PinLength=30|Location.X=490|Location.Y=188|Name=63|Designator=B-63|PinPropagationDelay=0.000000E+000
|RECORD=2|OwnerIndex=1728|OwnerPartId=2|FormalType=1|PinConglomerate=56|PinLength=30|Location.X=550|Location.Y=188|Name=64|Designator=B-64|PinPropagationDelay=0.000000E+000
|RECORD=2|OwnerIndex=1728|OwnerPartId=2|FormalType=1|PinConglomerate=58|PinLength=30|Location.X=490|Location.Y=178|Name=65|Designator=B-65|PinPropagationDelay=0.000000E+000
|RECORD=2|OwnerIndex=1728|OwnerPartId=2|FormalType=1|PinConglomerate=56|PinLength=30|Location.X=550|Location.Y=178|Name=66|Designator=B-66|PinPropagationDelay=0.000000E+000
|RECORD=2|OwnerIndex=1728|OwnerPartId=2|FormalType=1|PinConglomerate=58|PinLength=30|Location.X=490|Location.Y=168|Name=67|Designator=B-67|PinPropagationDelay=0.000000E+000
|RECORD=2|OwnerIndex=1728|OwnerPartId=2|FormalType=1|PinConglomerate=56|PinLength=30|Location.X=550|Location.Y=168|Name=68|Designator=B-68|PinPropagationDelay=0.000000E+000
|RECORD=2|OwnerIndex=1728|OwnerPartId=2|FormalType=1|PinConglomerate=58|PinLength=30|Location.X=490|Location.Y=158|Name=69|Designator=B-69|PinPropagationDelay=0.000000E+000
|RECORD=2|OwnerIndex=1728|OwnerPartId=2|FormalType=1|PinConglomerate=56|PinLength=30|Location.X=550|Location.Y=158|Name=70|Designator=B-70|PinPropagationDelay=0.000000E+000
|RECORD=2|OwnerIndex=1728|OwnerPartId=2|FormalType=1|PinConglomerate=58|PinLength=30|Location.X=490|Location.Y=148|Name=71|Designator=B-71|PinPropagationDelay=0.000000E+000
|RECORD=2|OwnerIndex=1728|OwnerPartId=2|FormalType=1|PinConglomerate=56|PinLength=30|Location.X=550|Location.Y=148|Name=72|Designator=B-72|PinPropagationDelay=0.000000E+000
|RECORD=2|OwnerIndex=1728|OwnerPartId=2|FormalType=1|PinConglomerate=58|PinLength=30|Location.X=490|Location.Y=138|Name=73|Designator=B-73|PinPropagationDelay=0.000000E+000
|RECORD=2|OwnerIndex=1728|OwnerPartId=2|FormalType=1|PinConglomerate=56|PinLength=30|Location.X=550|Location.Y=138|Name=74|Designator=B-74|PinPropagationDelay=0.000000E+000
|RECORD=2|OwnerIndex=1728|OwnerPartId=2|FormalType=1|PinConglomerate=58|PinLength=30|Location.X=490|Location.Y=128|Name=75|Designator=B-75|PinPropagationDelay=0.000000E+000
|RECORD=2|OwnerIndex=1728|OwnerPartId=2|FormalType=1|PinConglomerate=56|PinLength=30|Location.X=550|Location.Y=128|Name=76|Designator=B-76|PinPropagationDelay=0.000000E+000
|RECORD=2|OwnerIndex=1728|OwnerPartId=2|FormalType=1|PinConglomerate=58|PinLength=30|Location.X=490|Location.Y=118|Name=77|Designator=B-77|PinPropagationDelay=0.000000E+000
|RECORD=2|OwnerIndex=1728|OwnerPartId=2|FormalType=1|PinConglomerate=56|PinLength=30|Location.X=550|Location.Y=118|Name=78|Designator=B-78|PinPropagationDelay=0.000000E+000
|RECORD=2|OwnerIndex=1728|OwnerPartId=2|FormalType=1|PinConglomerate=58|PinLength=30|Location.X=490|Location.Y=108|Name=79|Designator=B-79|PinPropagationDelay=0.000000E+000
|RECORD=2|OwnerIndex=1728|OwnerPartId=2|FormalType=1|PinConglomerate=56|PinLength=30|Location.X=550|Location.Y=108|Name=80|Designator=B-80|PinPropagationDelay=0.000000E+000
|RECORD=2|OwnerIndex=1728|OwnerPartId=2|FormalType=1|PinConglomerate=58|PinLength=30|Location.X=490|Location.Y=98|Name=81|Designator=B-81|PinPropagationDelay=0.000000E+000
|RECORD=2|OwnerIndex=1728|OwnerPartId=2|FormalType=1|PinConglomerate=56|PinLength=30|Location.X=550|Location.Y=98|Name=82|Designator=B-82|PinPropagationDelay=0.000000E+000
|RECORD=2|OwnerIndex=1728|OwnerPartId=2|FormalType=1|PinConglomerate=58|PinLength=30|Location.X=490|Location.Y=88|Name=83|Designator=B-83|PinPropagationDelay=0.000000E+000
|RECORD=2|OwnerIndex=1728|OwnerPartId=2|FormalType=1|PinConglomerate=56|PinLength=30|Location.X=550|Location.Y=88|Name=84|Designator=B-84|PinPropagationDelay=0.000000E+000
|RECORD=14|OwnerIndex=1728|IsNotAccesible=T|IndexInSheet=85|OwnerPartId=3|Location.X=490|Location.Y=78|Corner.X=550|Corner.Y=508|Color=128|AreaColor=11599871|IsSolid=T
|RECORD=2|OwnerIndex=1728|OwnerPartId=3|FormalType=1|PinConglomerate=58|PinLength=30|Location.X=490|Location.Y=498|Name=1|Designator=C-1|PinPropagationDelay=0.000000E+000
|RECORD=2|OwnerIndex=1728|OwnerPartId=3|FormalType=1|PinConglomerate=56|PinLength=30|Location.X=550|Location.Y=498|Name=2|Designator=C-2|PinPropagationDelay=0.000000E+000
|RECORD=2|OwnerIndex=1728|OwnerPartId=3|FormalType=1|PinConglomerate=58|PinLength=30|Location.X=490|Location.Y=488|Name=3|Designator=C-3|PinPropagationDelay=0.000000E+000
|RECORD=2|OwnerIndex=1728|OwnerPartId=3|FormalType=1|PinConglomerate=56|PinLength=30|Location.X=550|Location.Y=488|Name=4|Designator=C-4|PinPropagationDelay=0.000000E+000
|RECORD=2|OwnerIndex=1728|OwnerPartId=3|FormalType=1|PinConglomerate=58|PinLength=30|Location.X=490|Location.Y=478|Name=5|Designator=C-5|PinPropagationDelay=0.000000E+000
|RECORD=2|OwnerIndex=1728|OwnerPartId=3|FormalType=1|PinConglomerate=56|PinLength=30|Location.X=550|Location.Y=478|Name=6|Designator=C-6|PinPropagationDelay=0.000000E+000
|RECORD=2|OwnerIndex=1728|OwnerPartId=3|FormalType=1|PinConglomerate=58|PinLength=30|Location.X=490|Location.Y=468|Name=7|Designator=C-7|PinPropagationDelay=0.000000E+000
|RECORD=2|OwnerIndex=1728|OwnerPartId=3|FormalType=1|PinConglomerate=56|PinLength=30|Location.X=550|Location.Y=468|Name=8|Designator=C-8|PinPropagationDelay=0.000000E+000
|RECORD=2|OwnerIndex=1728|OwnerPartId=3|FormalType=1|PinConglomerate=58|PinLength=30|Location.X=490|Location.Y=458|Name=9|Designator=C-9|PinPropagationDelay=0.000000E+000
|RECORD=2|OwnerIndex=1728|OwnerPartId=3|FormalType=1|PinConglomerate=56|PinLength=30|Location.X=550|Location.Y=458|Name=10|Designator=C-10|PinPropagationDelay=0.000000E+000
|RECORD=2|OwnerIndex=1728|OwnerPartId=3|FormalType=1|PinConglomerate=58|PinLength=30|Location.X=490|Location.Y=448|Name=11|Designator=C-11|PinPropagationDelay=0.000000E+000
|RECORD=2|OwnerIndex=1728|OwnerPartId=3|FormalType=1|PinConglomerate=56|PinLength=30|Location.X=550|Location.Y=448|Name=12|Designator=C-12|PinPropagationDelay=0.000000E+000
|RECORD=2|OwnerIndex=1728|OwnerPartId=3|FormalType=1|PinConglomerate=58|PinLength=30|Location.X=490|Location.Y=438|Name=13|Designator=C-13|PinPropagationDelay=0.000000E+000
|RECORD=2|OwnerIndex=1728|OwnerPartId=3|FormalType=1|PinConglomerate=56|PinLength=30|Location.X=550|Location.Y=438|Name=14|Designator=C-14|PinPropagationDelay=0.000000E+000
|RECORD=2|OwnerIndex=1728|OwnerPartId=3|FormalType=1|PinConglomerate=58|PinLength=30|Location.X=490|Location.Y=428|Name=15|Designator=C-15|PinPropagationDelay=0.000000E+000
|RECORD=2|OwnerIndex=1728|OwnerPartId=3|FormalType=1|PinConglomerate=56|PinLength=30|Location.X=550|Location.Y=428|Name=16|Designator=C-16|PinPropagationDelay=0.000000E+000
|RECORD=2|OwnerIndex=1728|OwnerPartId=3|FormalType=1|PinConglomerate=58|PinLength=30|Location.X=490|Location.Y=418|Name=17|Designator=C-17|PinPropagationDelay=0.000000E+000
|RECORD=2|OwnerIndex=1728|OwnerPartId=3|FormalType=1|PinConglomerate=56|PinLength=30|Location.X=550|Location.Y=418|Name=18|Designator=C-18|PinPropagationDelay=0.000000E+000
|RECORD=2|OwnerIndex=1728|OwnerPartId=3|FormalType=1|PinConglomerate=58|PinLength=30|Location.X=490|Location.Y=408|Name=19|Designator=C-19|PinPropagationDelay=0.000000E+000
|RECORD=2|OwnerIndex=1728|OwnerPartId=3|FormalType=1|PinConglomerate=56|PinLength=30|Location.X=550|Location.Y=408|Name=20|Designator=C-20|PinPropagationDelay=0.000000E+000
|RECORD=2|OwnerIndex=1728|OwnerPartId=3|FormalType=1|PinConglomerate=58|PinLength=30|Location.X=490|Location.Y=398|Name=21|Designator=C-21|PinPropagationDelay=0.000000E+000
|RECORD=2|OwnerIndex=1728|OwnerPartId=3|FormalType=1|PinConglomerate=56|PinLength=30|Location.X=550|Location.Y=398|Name=22|Designator=C-22|PinPropagationDelay=0.000000E+000
|RECORD=2|OwnerIndex=1728|OwnerPartId=3|FormalType=1|PinConglomerate=58|PinLength=30|Location.X=490|Location.Y=388|Name=23|Designator=C-23|PinPropagationDelay=0.000000E+000
|RECORD=2|OwnerIndex=1728|OwnerPartId=3|FormalType=1|PinConglomerate=56|PinLength=30|Location.X=550|Location.Y=388|Name=24|Designator=C-24|PinPropagationDelay=0.000000E+000
|RECORD=2|OwnerIndex=1728|OwnerPartId=3|FormalType=1|PinConglomerate=58|PinLength=30|Location.X=490|Location.Y=378|Name=25|Designator=C-25|PinPropagationDelay=0.000000E+000
|RECORD=2|OwnerIndex=1728|OwnerPartId=3|FormalType=1|PinConglomerate=56|PinLength=30|Location.X=550|Location.Y=378|Name=26|Designator=C-26|PinPropagationDelay=0.000000E+000
|RECORD=2|OwnerIndex=1728|OwnerPartId=3|FormalType=1|PinConglomerate=58|PinLength=30|Location.X=490|Location.Y=368|Name=27|Designator=C-27|PinPropagationDelay=0.000000E+000
|RECORD=2|OwnerIndex=1728|OwnerPartId=3|FormalType=1|PinConglomerate=56|PinLength=30|Location.X=550|Location.Y=368|Name=28|Designator=C-28|PinPropagationDelay=0.000000E+000
|RECORD=2|OwnerIndex=1728|OwnerPartId=3|FormalType=1|PinConglomerate=58|PinLength=30|Location.X=490|Location.Y=358|Name=29|Designator=C-29|PinPropagationDelay=0.000000E+000
|RECORD=2|OwnerIndex=1728|OwnerPartId=3|FormalType=1|PinConglomerate=56|PinLength=30|Location.X=550|Location.Y=358|Name=30|Designator=C-30|PinPropagationDelay=0.000000E+000
|RECORD=2|OwnerIndex=1728|OwnerPartId=3|FormalType=1|PinConglomerate=58|PinLength=30|Location.X=490|Location.Y=348|Name=31|Designator=C-31|PinPropagationDelay=0.000000E+000
|RECORD=2|OwnerIndex=1728|OwnerPartId=3|FormalType=1|PinConglomerate=56|PinLength=30|Location.X=550|Location.Y=348|Name=32|Designator=C-32|PinPropagationDelay=0.000000E+000
|RECORD=2|OwnerIndex=1728|OwnerPartId=3|FormalType=1|PinConglomerate=58|PinLength=30|Location.X=490|Location.Y=338|Name=33|Designator=C-33|PinPropagationDelay=0.000000E+000
|RECORD=2|OwnerIndex=1728|OwnerPartId=3|FormalType=1|PinConglomerate=56|PinLength=30|Location.X=550|Location.Y=338|Name=34|Designator=C-34|PinPropagationDelay=0.000000E+000
|RECORD=2|OwnerIndex=1728|OwnerPartId=3|FormalType=1|PinConglomerate=58|PinLength=30|Location.X=490|Location.Y=328|Name=35|Designator=C-35|PinPropagationDelay=0.000000E+000
|RECORD=2|OwnerIndex=1728|OwnerPartId=3|FormalType=1|PinConglomerate=56|PinLength=30|Location.X=550|Location.Y=328|Name=36|Designator=C-36|PinPropagationDelay=0.000000E+000
|RECORD=2|OwnerIndex=1728|OwnerPartId=3|FormalType=1|PinConglomerate=58|PinLength=30|Location.X=490|Location.Y=318|Name=37|Designator=C-37|PinPropagationDelay=0.000000E+000
|RECORD=2|OwnerIndex=1728|OwnerPartId=3|FormalType=1|PinConglomerate=56|PinLength=30|Location.X=550|Location.Y=318|Name=38|Designator=C-38|PinPropagationDelay=0.000000E+000
|RECORD=2|OwnerIndex=1728|OwnerPartId=3|FormalType=1|PinConglomerate=58|PinLength=30|Location.X=490|Location.Y=308|Name=39|Designator=C-39|PinPropagationDelay=0.000000E+000
|RECORD=2|OwnerIndex=1728|OwnerPartId=3|FormalType=1|PinConglomerate=56|PinLength=30|Location.X=550|Location.Y=308|Name=40|Designator=C-40|PinPropagationDelay=0.000000E+000
|RECORD=2|OwnerIndex=1728|OwnerPartId=3|FormalType=1|PinConglomerate=58|PinLength=30|Location.X=490|Location.Y=298|Name=41|Designator=C-41|PinPropagationDelay=0.000000E+000
|RECORD=2|OwnerIndex=1728|OwnerPartId=3|FormalType=1|PinConglomerate=56|PinLength=30|Location.X=550|Location.Y=298|Name=42|Designator=C-42|PinPropagationDelay=0.000000E+000
|RECORD=2|OwnerIndex=1728|OwnerPartId=3|FormalType=1|PinConglomerate=58|PinLength=30|Location.X=490|Location.Y=288|Name=43|Designator=C-43|PinPropagationDelay=0.000000E+000
|RECORD=2|OwnerIndex=1728|OwnerPartId=3|FormalType=1|PinConglomerate=56|PinLength=30|Location.X=550|Location.Y=288|Name=44|Designator=C-44|PinPropagationDelay=0.000000E+000
|RECORD=2|OwnerIndex=1728|OwnerPartId=3|FormalType=1|PinConglomerate=58|PinLength=30|Location.X=490|Location.Y=278|Name=45|Designator=C-45|PinPropagationDelay=0.000000E+000
|RECORD=2|OwnerIndex=1728|OwnerPartId=3|FormalType=1|PinConglomerate=56|PinLength=30|Location.X=550|Location.Y=278|Name=46|Designator=C-46|PinPropagationDelay=0.000000E+000
|RECORD=2|OwnerIndex=1728|OwnerPartId=3|FormalType=1|PinConglomerate=58|PinLength=30|Location.X=490|Location.Y=268|Name=47|Designator=C-47|PinPropagationDelay=0.000000E+000
|RECORD=2|OwnerIndex=1728|OwnerPartId=3|FormalType=1|PinConglomerate=56|PinLength=30|Location.X=550|Location.Y=268|Name=48|Designator=C-48|PinPropagationDelay=0.000000E+000
|RECORD=2|OwnerIndex=1728|OwnerPartId=3|FormalType=1|PinConglomerate=58|PinLength=30|Location.X=490|Location.Y=258|Name=49|Designator=C-49|PinPropagationDelay=0.000000E+000
|RECORD=2|OwnerIndex=1728|OwnerPartId=3|FormalType=1|PinConglomerate=56|PinLength=30|Location.X=550|Location.Y=258|Name=50|Designator=C-50|PinPropagationDelay=0.000000E+000
|RECORD=2|OwnerIndex=1728|OwnerPartId=3|FormalType=1|PinConglomerate=58|PinLength=30|Location.X=490|Location.Y=248|Name=51|Designator=C-51|PinPropagationDelay=0.000000E+000
|RECORD=2|OwnerIndex=1728|OwnerPartId=3|FormalType=1|PinConglomerate=56|PinLength=30|Location.X=550|Location.Y=248|Name=52|Designator=C-52|PinPropagationDelay=0.000000E+000
|RECORD=2|OwnerIndex=1728|OwnerPartId=3|FormalType=1|PinConglomerate=58|PinLength=30|Location.X=490|Location.Y=238|Name=53|Designator=C-53|PinPropagationDelay=0.000000E+000
|RECORD=2|OwnerIndex=1728|OwnerPartId=3|FormalType=1|PinConglomerate=56|PinLength=30|Location.X=550|Location.Y=238|Name=54|Designator=C-54|PinPropagationDelay=0.000000E+000
|RECORD=2|OwnerIndex=1728|OwnerPartId=3|FormalType=1|PinConglomerate=58|PinLength=30|Location.X=490|Location.Y=228|Name=55|Designator=C-55|PinPropagationDelay=0.000000E+000
|RECORD=2|OwnerIndex=1728|OwnerPartId=3|FormalType=1|PinConglomerate=56|PinLength=30|Location.X=550|Location.Y=228|Name=56|Designator=C-56|PinPropagationDelay=0.000000E+000
|RECORD=2|OwnerIndex=1728|OwnerPartId=3|FormalType=1|PinConglomerate=58|PinLength=30|Location.X=490|Location.Y=218|Name=57|Designator=C-57|PinPropagationDelay=0.000000E+000
|RECORD=2|OwnerIndex=1728|OwnerPartId=3|FormalType=1|PinConglomerate=56|PinLength=30|Location.X=550|Location.Y=218|Name=58|Designator=C-58|PinPropagationDelay=0.000000E+000
|RECORD=2|OwnerIndex=1728|OwnerPartId=3|FormalType=1|PinConglomerate=58|PinLength=30|Location.X=490|Location.Y=208|Name=59|Designator=C-59|PinPropagationDelay=0.000000E+000
|RECORD=2|OwnerIndex=1728|OwnerPartId=3|FormalType=1|PinConglomerate=56|PinLength=30|Location.X=550|Location.Y=208|Name=60|Designator=C-60|PinPropagationDelay=0.000000E+000
|RECORD=2|OwnerIndex=1728|OwnerPartId=3|FormalType=1|PinConglomerate=58|PinLength=30|Location.X=490|Location.Y=198|Name=61|Designator=C-61|PinPropagationDelay=0.000000E+000
|RECORD=2|OwnerIndex=1728|OwnerPartId=3|FormalType=1|PinConglomerate=56|PinLength=30|Location.X=550|Location.Y=198|Name=62|Designator=C-62|PinPropagationDelay=0.000000E+000
|RECORD=2|OwnerIndex=1728|OwnerPartId=3|FormalType=1|PinConglomerate=58|PinLength=30|Location.X=490|Location.Y=188|Name=63|Designator=C-63|PinPropagationDelay=0.000000E+000
|RECORD=2|OwnerIndex=1728|OwnerPartId=3|FormalType=1|PinConglomerate=56|PinLength=30|Location.X=550|Location.Y=188|Name=64|Designator=C-64|PinPropagationDelay=0.000000E+000
|RECORD=2|OwnerIndex=1728|OwnerPartId=3|FormalType=1|PinConglomerate=58|PinLength=30|Location.X=490|Location.Y=178|Name=65|Designator=C-65|PinPropagationDelay=0.000000E+000
|RECORD=2|OwnerIndex=1728|OwnerPartId=3|FormalType=1|PinConglomerate=56|PinLength=30|Location.X=550|Location.Y=178|Name=66|Designator=C-66|PinPropagationDelay=0.000000E+000
|RECORD=2|OwnerIndex=1728|OwnerPartId=3|FormalType=1|PinConglomerate=58|PinLength=30|Location.X=490|Location.Y=168|Name=67|Designator=C-67|PinPropagationDelay=0.000000E+000
|RECORD=2|OwnerIndex=1728|OwnerPartId=3|FormalType=1|PinConglomerate=56|PinLength=30|Location.X=550|Location.Y=168|Name=68|Designator=C-68|PinPropagationDelay=0.000000E+000
|RECORD=2|OwnerIndex=1728|OwnerPartId=3|FormalType=1|PinConglomerate=58|PinLength=30|Location.X=490|Location.Y=158|Name=69|Designator=C-69|PinPropagationDelay=0.000000E+000
|RECORD=2|OwnerIndex=1728|OwnerPartId=3|FormalType=1|PinConglomerate=56|PinLength=30|Location.X=550|Location.Y=158|Name=70|Designator=C-70|PinPropagationDelay=0.000000E+000
|RECORD=2|OwnerIndex=1728|OwnerPartId=3|FormalType=1|PinConglomerate=58|PinLength=30|Location.X=490|Location.Y=148|Name=71|Designator=C-71|PinPropagationDelay=0.000000E+000
|RECORD=2|OwnerIndex=1728|OwnerPartId=3|FormalType=1|PinConglomerate=56|PinLength=30|Location.X=550|Location.Y=148|Name=72|Designator=C-72|PinPropagationDelay=0.000000E+000
|RECORD=2|OwnerIndex=1728|OwnerPartId=3|FormalType=1|PinConglomerate=58|PinLength=30|Location.X=490|Location.Y=138|Name=73|Designator=C-73|PinPropagationDelay=0.000000E+000
|RECORD=2|OwnerIndex=1728|OwnerPartId=3|FormalType=1|PinConglomerate=56|PinLength=30|Location.X=550|Location.Y=138|Name=74|Designator=C-74|PinPropagationDelay=0.000000E+000
|RECORD=2|OwnerIndex=1728|OwnerPartId=3|FormalType=1|PinConglomerate=58|PinLength=30|Location.X=490|Location.Y=128|Name=75|Designator=C-75|PinPropagationDelay=0.000000E+000
|RECORD=2|OwnerIndex=1728|OwnerPartId=3|FormalType=1|PinConglomerate=56|PinLength=30|Location.X=550|Location.Y=128|Name=76|Designator=C-76|PinPropagationDelay=0.000000E+000
|RECORD=2|OwnerIndex=1728|OwnerPartId=3|FormalType=1|PinConglomerate=58|PinLength=30|Location.X=490|Location.Y=118|Name=77|Designator=C-77|PinPropagationDelay=0.000000E+000
|RECORD=2|OwnerIndex=1728|OwnerPartId=3|FormalType=1|PinConglomerate=56|PinLength=30|Location.X=550|Location.Y=118|Name=78|Designator=C-78|PinPropagationDelay=0.000000E+000
|RECORD=2|OwnerIndex=1728|OwnerPartId=3|FormalType=1|PinConglomerate=58|PinLength=30|Location.X=490|Location.Y=108|Name=79|Designator=C-79|PinPropagationDelay=0.000000E+000
|RECORD=2|OwnerIndex=1728|OwnerPartId=3|FormalType=1|PinConglomerate=56|PinLength=30|Location.X=550|Location.Y=108|Name=80|Designator=C-80|PinPropagationDelay=0.000000E+000
|RECORD=2|OwnerIndex=1728|OwnerPartId=3|FormalType=1|PinConglomerate=58|PinLength=30|Location.X=490|Location.Y=98|Name=81|Designator=C-81|PinPropagationDelay=0.000000E+000
|RECORD=2|OwnerIndex=1728|OwnerPartId=3|FormalType=1|PinConglomerate=56|PinLength=30|Location.X=550|Location.Y=98|Name=82|Designator=C-82|PinPropagationDelay=0.000000E+000
|RECORD=2|OwnerIndex=1728|OwnerPartId=3|FormalType=1|PinConglomerate=58|PinLength=30|Location.X=490|Location.Y=88|Name=83|Designator=C-83|PinPropagationDelay=0.000000E+000
|RECORD=2|OwnerIndex=1728|OwnerPartId=3|FormalType=1|PinConglomerate=56|PinLength=30|Location.X=550|Location.Y=88|Name=84|Designator=C-84|PinPropagationDelay=0.000000E+000
|RECORD=14|OwnerIndex=1728|IsNotAccesible=T|IndexInSheet=170|OwnerPartId=4|Location.X=490|Location.Y=78|Corner.X=550|Corner.Y=508|Color=128|AreaColor=11599871|IsSolid=T
|RECORD=2|OwnerIndex=1728|OwnerPartId=4|FormalType=1|PinConglomerate=58|PinLength=30|Location.X=490|Location.Y=498|Name=1|Designator=D-1|PinPropagationDelay=0.000000E+000
|RECORD=2|OwnerIndex=1728|OwnerPartId=4|FormalType=1|PinConglomerate=56|PinLength=30|Location.X=550|Location.Y=498|Name=2|Designator=D-2|PinPropagationDelay=0.000000E+000
|RECORD=2|OwnerIndex=1728|OwnerPartId=4|FormalType=1|PinConglomerate=58|PinLength=30|Location.X=490|Location.Y=488|Name=3|Designator=D-3|PinPropagationDelay=0.000000E+000
|RECORD=2|OwnerIndex=1728|OwnerPartId=4|FormalType=1|PinConglomerate=56|PinLength=30|Location.X=550|Location.Y=488|Name=4|Designator=D-4|PinPropagationDelay=0.000000E+000
|RECORD=2|OwnerIndex=1728|OwnerPartId=4|FormalType=1|PinConglomerate=58|PinLength=30|Location.X=490|Location.Y=478|Name=5|Designator=D-5|PinPropagationDelay=0.000000E+000
|RECORD=2|OwnerIndex=1728|OwnerPartId=4|FormalType=1|PinConglomerate=56|PinLength=30|Location.X=550|Location.Y=478|Name=6|Designator=D-6|PinPropagationDelay=0.000000E+000
|RECORD=2|OwnerIndex=1728|OwnerPartId=4|FormalType=1|PinConglomerate=58|PinLength=30|Location.X=490|Location.Y=468|Name=7|Designator=D-7|PinPropagationDelay=0.000000E+000
|RECORD=2|OwnerIndex=1728|OwnerPartId=4|FormalType=1|PinConglomerate=56|PinLength=30|Location.X=550|Location.Y=468|Name=8|Designator=D-8|PinPropagationDelay=0.000000E+000
|RECORD=2|OwnerIndex=1728|OwnerPartId=4|FormalType=1|PinConglomerate=58|PinLength=30|Location.X=490|Location.Y=458|Name=9|Designator=D-9|PinPropagationDelay=0.000000E+000
|RECORD=2|OwnerIndex=1728|OwnerPartId=4|FormalType=1|PinConglomerate=56|PinLength=30|Location.X=550|Location.Y=458|Name=10|Designator=D-10|PinPropagationDelay=0.000000E+000
|RECORD=2|OwnerIndex=1728|OwnerPartId=4|FormalType=1|PinConglomerate=58|PinLength=30|Location.X=490|Location.Y=448|Name=11|Designator=D-11|PinPropagationDelay=0.000000E+000
|RECORD=2|OwnerIndex=1728|OwnerPartId=4|FormalType=1|PinConglomerate=56|PinLength=30|Location.X=550|Location.Y=448|Name=12|Designator=D-12|PinPropagationDelay=0.000000E+000
|RECORD=2|OwnerIndex=1728|OwnerPartId=4|FormalType=1|PinConglomerate=58|PinLength=30|Location.X=490|Location.Y=438|Name=13|Designator=D-13|PinPropagationDelay=0.000000E+000
|RECORD=2|OwnerIndex=1728|OwnerPartId=4|FormalType=1|PinConglomerate=56|PinLength=30|Location.X=550|Location.Y=438|Name=14|Designator=D-14|PinPropagationDelay=0.000000E+000
|RECORD=2|OwnerIndex=1728|OwnerPartId=4|FormalType=1|PinConglomerate=58|PinLength=30|Location.X=490|Location.Y=428|Name=15|Designator=D-15|PinPropagationDelay=0.000000E+000
|RECORD=2|OwnerIndex=1728|OwnerPartId=4|FormalType=1|PinConglomerate=56|PinLength=30|Location.X=550|Location.Y=428|Name=16|Designator=D-16|PinPropagationDelay=0.000000E+000
|RECORD=2|OwnerIndex=1728|OwnerPartId=4|FormalType=1|PinConglomerate=58|PinLength=30|Location.X=490|Location.Y=418|Name=17|Designator=D-17|PinPropagationDelay=0.000000E+000
|RECORD=2|OwnerIndex=1728|OwnerPartId=4|FormalType=1|PinConglomerate=56|PinLength=30|Location.X=550|Location.Y=418|Name=18|Designator=D-18|PinPropagationDelay=0.000000E+000
|RECORD=2|OwnerIndex=1728|OwnerPartId=4|FormalType=1|PinConglomerate=58|PinLength=30|Location.X=490|Location.Y=408|Name=19|Designator=D-19|PinPropagationDelay=0.000000E+000
|RECORD=2|OwnerIndex=1728|OwnerPartId=4|FormalType=1|PinConglomerate=56|PinLength=30|Location.X=550|Location.Y=408|Name=20|Designator=D-20|PinPropagationDelay=0.000000E+000
|RECORD=2|OwnerIndex=1728|OwnerPartId=4|FormalType=1|PinConglomerate=58|PinLength=30|Location.X=490|Location.Y=398|Name=21|Designator=D-21|PinPropagationDelay=0.000000E+000
|RECORD=2|OwnerIndex=1728|OwnerPartId=4|FormalType=1|PinConglomerate=56|PinLength=30|Location.X=550|Location.Y=398|Name=22|Designator=D-22|PinPropagationDelay=0.000000E+000
|RECORD=2|OwnerIndex=1728|OwnerPartId=4|FormalType=1|PinConglomerate=58|PinLength=30|Location.X=490|Location.Y=388|Name=23|Designator=D-23|PinPropagationDelay=0.000000E+000
|RECORD=2|OwnerIndex=1728|OwnerPartId=4|FormalType=1|PinConglomerate=56|PinLength=30|Location.X=550|Location.Y=388|Name=24|Designator=D-24|PinPropagationDelay=0.000000E+000
|RECORD=2|OwnerIndex=1728|OwnerPartId=4|FormalType=1|PinConglomerate=58|PinLength=30|Location.X=490|Location.Y=378|Name=25|Designator=D-25|PinPropagationDelay=0.000000E+000
|RECORD=2|OwnerIndex=1728|OwnerPartId=4|FormalType=1|PinConglomerate=56|PinLength=30|Location.X=550|Location.Y=378|Name=26|Designator=D-26|PinPropagationDelay=0.000000E+000
|RECORD=2|OwnerIndex=1728|OwnerPartId=4|FormalType=1|PinConglomerate=58|PinLength=30|Location.X=490|Location.Y=368|Name=27|Designator=D-27|PinPropagationDelay=0.000000E+000
|RECORD=2|OwnerIndex=1728|OwnerPartId=4|FormalType=1|PinConglomerate=56|PinLength=30|Location.X=550|Location.Y=368|Name=28|Designator=D-28|PinPropagationDelay=0.000000E+000
|RECORD=2|OwnerIndex=1728|OwnerPartId=4|FormalType=1|PinConglomerate=58|PinLength=30|Location.X=490|Location.Y=358|Name=29|Designator=D-29|PinPropagationDelay=0.000000E+000
|RECORD=2|OwnerIndex=1728|OwnerPartId=4|FormalType=1|PinConglomerate=56|PinLength=30|Location.X=550|Location.Y=358|Name=30|Designator=D-30|PinPropagationDelay=0.000000E+000
|RECORD=2|OwnerIndex=1728|OwnerPartId=4|FormalType=1|PinConglomerate=58|PinLength=30|Location.X=490|Location.Y=348|Name=31|Designator=D-31|PinPropagationDelay=0.000000E+000
|RECORD=2|OwnerIndex=1728|OwnerPartId=4|FormalType=1|PinConglomerate=56|PinLength=30|Location.X=550|Location.Y=348|Name=32|Designator=D-32|PinPropagationDelay=0.000000E+000
|RECORD=2|OwnerIndex=1728|OwnerPartId=4|FormalType=1|PinConglomerate=58|PinLength=30|Location.X=490|Location.Y=338|Name=33|Designator=D-33|PinPropagationDelay=0.000000E+000
|RECORD=2|OwnerIndex=1728|OwnerPartId=4|FormalType=1|PinConglomerate=56|PinLength=30|Location.X=550|Location.Y=338|Name=34|Designator=D-34|PinPropagationDelay=0.000000E+000
|RECORD=2|OwnerIndex=1728|OwnerPartId=4|FormalType=1|PinConglomerate=58|PinLength=30|Location.X=490|Location.Y=328|Name=35|Designator=D-35|PinPropagationDelay=0.000000E+000
|RECORD=2|OwnerIndex=1728|OwnerPartId=4|FormalType=1|PinConglomerate=56|PinLength=30|Location.X=550|Location.Y=328|Name=36|Designator=D-36|PinPropagationDelay=0.000000E+000
|RECORD=2|OwnerIndex=1728|OwnerPartId=4|FormalType=1|PinConglomerate=58|PinLength=30|Location.X=490|Location.Y=318|Name=37|Designator=D-37|PinPropagationDelay=0.000000E+000
|RECORD=2|OwnerIndex=1728|OwnerPartId=4|FormalType=1|PinConglomerate=56|PinLength=30|Location.X=550|Location.Y=318|Name=38|Designator=D-38|PinPropagationDelay=0.000000E+000
|RECORD=2|OwnerIndex=1728|OwnerPartId=4|FormalType=1|PinConglomerate=58|PinLength=30|Location.X=490|Location.Y=308|Name=39|Designator=D-39|PinPropagationDelay=0.000000E+000
|RECORD=2|OwnerIndex=1728|OwnerPartId=4|FormalType=1|PinConglomerate=56|PinLength=30|Location.X=550|Location.Y=308|Name=40|Designator=D-40|PinPropagationDelay=0.000000E+000
|RECORD=2|OwnerIndex=1728|OwnerPartId=4|FormalType=1|PinConglomerate=58|PinLength=30|Location.X=490|Location.Y=298|Name=41|Designator=D-41|PinPropagationDelay=0.000000E+000
|RECORD=2|OwnerIndex=1728|OwnerPartId=4|FormalType=1|PinConglomerate=56|PinLength=30|Location.X=550|Location.Y=298|Name=42|Designator=D-42|PinPropagationDelay=0.000000E+000
|RECORD=2|OwnerIndex=1728|OwnerPartId=4|FormalType=1|PinConglomerate=58|PinLength=30|Location.X=490|Location.Y=288|Name=43|Designator=D-43|PinPropagationDelay=0.000000E+000
|RECORD=2|OwnerIndex=1728|OwnerPartId=4|FormalType=1|PinConglomerate=56|PinLength=30|Location.X=550|Location.Y=288|Name=44|Designator=D-44|PinPropagationDelay=0.000000E+000
|RECORD=2|OwnerIndex=1728|OwnerPartId=4|FormalType=1|PinConglomerate=58|PinLength=30|Location.X=490|Location.Y=278|Name=45|Designator=D-45|PinPropagationDelay=0.000000E+000
|RECORD=2|OwnerIndex=1728|OwnerPartId=4|FormalType=1|PinConglomerate=56|PinLength=30|Location.X=550|Location.Y=278|Name=46|Designator=D-46|PinPropagationDelay=0.000000E+000
|RECORD=2|OwnerIndex=1728|OwnerPartId=4|FormalType=1|PinConglomerate=58|PinLength=30|Location.X=490|Location.Y=268|Name=47|Designator=D-47|PinPropagationDelay=0.000000E+000
|RECORD=2|OwnerIndex=1728|OwnerPartId=4|FormalType=1|PinConglomerate=56|PinLength=30|Location.X=550|Location.Y=268|Name=48|Designator=D-48|PinPropagationDelay=0.000000E+000
|RECORD=2|OwnerIndex=1728|OwnerPartId=4|FormalType=1|PinConglomerate=58|PinLength=30|Location.X=490|Location.Y=258|Name=49|Designator=D-49|PinPropagationDelay=0.000000E+000
|RECORD=2|OwnerIndex=1728|OwnerPartId=4|FormalType=1|PinConglomerate=56|PinLength=30|Location.X=550|Location.Y=258|Name=50|Designator=D-50|PinPropagationDelay=0.000000E+000
|RECORD=2|OwnerIndex=1728|OwnerPartId=4|FormalType=1|PinConglomerate=58|PinLength=30|Location.X=490|Location.Y=248|Name=51|Designator=D-51|PinPropagationDelay=0.000000E+000
|RECORD=2|OwnerIndex=1728|OwnerPartId=4|FormalType=1|PinConglomerate=56|PinLength=30|Location.X=550|Location.Y=248|Name=52|Designator=D-52|PinPropagationDelay=0.000000E+000
|RECORD=2|OwnerIndex=1728|OwnerPartId=4|FormalType=1|PinConglomerate=58|PinLength=30|Location.X=490|Location.Y=238|Name=53|Designator=D-53|PinPropagationDelay=0.000000E+000
|RECORD=2|OwnerIndex=1728|OwnerPartId=4|FormalType=1|PinConglomerate=56|PinLength=30|Location.X=550|Location.Y=238|Name=54|Designator=D-54|PinPropagationDelay=0.000000E+000
|RECORD=2|OwnerIndex=1728|OwnerPartId=4|FormalType=1|PinConglomerate=58|PinLength=30|Location.X=490|Location.Y=228|Name=55|Designator=D-55|PinPropagationDelay=0.000000E+000
|RECORD=2|OwnerIndex=1728|OwnerPartId=4|FormalType=1|PinConglomerate=56|PinLength=30|Location.X=550|Location.Y=228|Name=56|Designator=D-56|PinPropagationDelay=0.000000E+000
|RECORD=2|OwnerIndex=1728|OwnerPartId=4|FormalType=1|PinConglomerate=58|PinLength=30|Location.X=490|Location.Y=218|Name=57|Designator=D-57|PinPropagationDelay=0.000000E+000
|RECORD=2|OwnerIndex=1728|OwnerPartId=4|FormalType=1|PinConglomerate=56|PinLength=30|Location.X=550|Location.Y=218|Name=58|Designator=D-58|PinPropagationDelay=0.000000E+000
|RECORD=2|OwnerIndex=1728|OwnerPartId=4|FormalType=1|PinConglomerate=58|PinLength=30|Location.X=490|Location.Y=208|Name=59|Designator=D-59|PinPropagationDelay=0.000000E+000
|RECORD=2|OwnerIndex=1728|OwnerPartId=4|FormalType=1|PinConglomerate=56|PinLength=30|Location.X=550|Location.Y=208|Name=60|Designator=D-60|PinPropagationDelay=0.000000E+000
|RECORD=2|OwnerIndex=1728|OwnerPartId=4|FormalType=1|PinConglomerate=58|PinLength=30|Location.X=490|Location.Y=198|Name=61|Designator=D-61|PinPropagationDelay=0.000000E+000
|RECORD=2|OwnerIndex=1728|OwnerPartId=4|FormalType=1|PinConglomerate=56|PinLength=30|Location.X=550|Location.Y=198|Name=62|Designator=D-62|PinPropagationDelay=0.000000E+000
|RECORD=2|OwnerIndex=1728|OwnerPartId=4|FormalType=1|PinConglomerate=58|PinLength=30|Location.X=490|Location.Y=188|Name=63|Designator=D-63|PinPropagationDelay=0.000000E+000
|RECORD=2|OwnerIndex=1728|OwnerPartId=4|FormalType=1|PinConglomerate=56|PinLength=30|Location.X=550|Location.Y=188|Name=64|Designator=D-64|PinPropagationDelay=0.000000E+000
|RECORD=2|OwnerIndex=1728|OwnerPartId=4|FormalType=1|PinConglomerate=58|PinLength=30|Location.X=490|Location.Y=178|Name=65|Designator=D-65|PinPropagationDelay=0.000000E+000
|RECORD=2|OwnerIndex=1728|OwnerPartId=4|FormalType=1|PinConglomerate=56|PinLength=30|Location.X=550|Location.Y=178|Name=66|Designator=D-66|PinPropagationDelay=0.000000E+000
|RECORD=2|OwnerIndex=1728|OwnerPartId=4|FormalType=1|PinConglomerate=58|PinLength=30|Location.X=490|Location.Y=168|Name=67|Designator=D-67|PinPropagationDelay=0.000000E+000
|RECORD=2|OwnerIndex=1728|OwnerPartId=4|FormalType=1|PinConglomerate=56|PinLength=30|Location.X=550|Location.Y=168|Name=68|Designator=D-68|PinPropagationDelay=0.000000E+000
|RECORD=2|OwnerIndex=1728|OwnerPartId=4|FormalType=1|PinConglomerate=58|PinLength=30|Location.X=490|Location.Y=158|Name=69|Designator=D-69|PinPropagationDelay=0.000000E+000
|RECORD=2|OwnerIndex=1728|OwnerPartId=4|FormalType=1|PinConglomerate=56|PinLength=30|Location.X=550|Location.Y=158|Name=70|Designator=D-70|PinPropagationDelay=0.000000E+000
|RECORD=2|OwnerIndex=1728|OwnerPartId=4|FormalType=1|PinConglomerate=58|PinLength=30|Location.X=490|Location.Y=148|Name=71|Designator=D-71|PinPropagationDelay=0.000000E+000
|RECORD=2|OwnerIndex=1728|OwnerPartId=4|FormalType=1|PinConglomerate=56|PinLength=30|Location.X=550|Location.Y=148|Name=72|Designator=D-72|PinPropagationDelay=0.000000E+000
|RECORD=2|OwnerIndex=1728|OwnerPartId=4|FormalType=1|PinConglomerate=58|PinLength=30|Location.X=490|Location.Y=138|Name=73|Designator=D-73|PinPropagationDelay=0.000000E+000
|RECORD=2|OwnerIndex=1728|OwnerPartId=4|FormalType=1|PinConglomerate=56|PinLength=30|Location.X=550|Location.Y=138|Name=74|Designator=D-74|PinPropagationDelay=0.000000E+000
|RECORD=2|OwnerIndex=1728|OwnerPartId=4|FormalType=1|PinConglomerate=58|PinLength=30|Location.X=490|Location.Y=128|Name=75|Designator=D-75|PinPropagationDelay=0.000000E+000
|RECORD=2|OwnerIndex=1728|OwnerPartId=4|FormalType=1|PinConglomerate=56|PinLength=30|Location.X=550|Location.Y=128|Name=76|Designator=D-76|PinPropagationDelay=0.000000E+000
|RECORD=2|OwnerIndex=1728|OwnerPartId=4|FormalType=1|PinConglomerate=58|PinLength=30|Location.X=490|Location.Y=118|Name=77|Designator=D-77|PinPropagationDelay=0.000000E+000
|RECORD=2|OwnerIndex=1728|OwnerPartId=4|FormalType=1|PinConglomerate=56|PinLength=30|Location.X=550|Location.Y=118|Name=78|Designator=D-78|PinPropagationDelay=0.000000E+000
|RECORD=2|OwnerIndex=1728|OwnerPartId=4|FormalType=1|PinConglomerate=58|PinLength=30|Location.X=490|Location.Y=108|Name=79|Designator=D-79|PinPropagationDelay=0.000000E+000
|RECORD=2|OwnerIndex=1728|OwnerPartId=4|FormalType=1|PinConglomerate=56|PinLength=30|Location.X=550|Location.Y=108|Name=80|Designator=D-80|PinPropagationDelay=0.000000E+000
|RECORD=2|OwnerIndex=1728|OwnerPartId=4|FormalType=1|PinConglomerate=58|PinLength=30|Location.X=490|Location.Y=98|Name=81|Designator=D-81|PinPropagationDelay=0.000000E+000
|RECORD=2|OwnerIndex=1728|OwnerPartId=4|FormalType=1|PinConglomerate=56|PinLength=30|Location.X=550|Location.Y=98|Name=82|Designator=D-82|PinPropagationDelay=0.000000E+000
|RECORD=2|OwnerIndex=1728|OwnerPartId=4|FormalType=1|PinConglomerate=58|PinLength=30|Location.X=490|Location.Y=88|Name=83|Designator=D-83|PinPropagationDelay=0.000000E+000
|RECORD=2|OwnerIndex=1728|OwnerPartId=4|FormalType=1|PinConglomerate=56|PinLength=30|Location.X=550|Location.Y=88|Name=84|Designator=D-84|PinPropagationDelay=0.000000E+000
|RECORD=14|OwnerIndex=1728|IsNotAccesible=T|IndexInSheet=255|OwnerPartId=1|Location.X=490|Location.Y=78|Corner.X=550|Corner.Y=508|Color=128|AreaColor=11599871|IsSolid=T
|RECORD=2|OwnerIndex=1728|OwnerPartId=1|FormalType=1|PinConglomerate=58|PinLength=30|Location.X=490|Location.Y=498|Name=1|Designator=A-1|PinPropagationDelay=0.000000E+000
|RECORD=2|OwnerIndex=1728|OwnerPartId=1|FormalType=1|PinConglomerate=56|PinLength=30|Location.X=550|Location.Y=498|Name=2|Designator=A-2|PinPropagationDelay=0.000000E+000
|RECORD=2|OwnerIndex=1728|OwnerPartId=1|FormalType=1|PinConglomerate=58|PinLength=30|Location.X=490|Location.Y=488|Name=3|Designator=A-3|PinPropagationDelay=0.000000E+000
|RECORD=2|OwnerIndex=1728|OwnerPartId=1|FormalType=1|PinConglomerate=56|PinLength=30|Location.X=550|Location.Y=488|Name=4|Designator=A-4|PinPropagationDelay=0.000000E+000
|RECORD=2|OwnerIndex=1728|OwnerPartId=1|FormalType=1|PinConglomerate=58|PinLength=30|Location.X=490|Location.Y=478|Name=5|Designator=A-5|PinPropagationDelay=0.000000E+000
|RECORD=2|OwnerIndex=1728|OwnerPartId=1|FormalType=1|PinConglomerate=56|PinLength=30|Location.X=550|Location.Y=478|Name=6|Designator=A-6|PinPropagationDelay=0.000000E+000
|RECORD=2|OwnerIndex=1728|OwnerPartId=1|FormalType=1|PinConglomerate=58|PinLength=30|Location.X=490|Location.Y=468|Name=7|Designator=A-7|PinPropagationDelay=0.000000E+000
|RECORD=2|OwnerIndex=1728|OwnerPartId=1|FormalType=1|PinConglomerate=56|PinLength=30|Location.X=550|Location.Y=468|Name=8|Designator=A-8|PinPropagationDelay=0.000000E+000
|RECORD=2|OwnerIndex=1728|OwnerPartId=1|FormalType=1|PinConglomerate=58|PinLength=30|Location.X=490|Location.Y=458|Name=9|Designator=A-9|PinPropagationDelay=0.000000E+000
|RECORD=2|OwnerIndex=1728|OwnerPartId=1|FormalType=1|PinConglomerate=56|PinLength=30|Location.X=550|Location.Y=458|Name=10|Designator=A-10|PinPropagationDelay=0.000000E+000
|RECORD=2|OwnerIndex=1728|OwnerPartId=1|FormalType=1|PinConglomerate=58|PinLength=30|Location.X=490|Location.Y=448|Name=11|Designator=A-11|PinPropagationDelay=0.000000E+000
|RECORD=2|OwnerIndex=1728|OwnerPartId=1|FormalType=1|PinConglomerate=56|PinLength=30|Location.X=550|Location.Y=448|Name=12|Designator=A-12|PinPropagationDelay=0.000000E+000
|RECORD=2|OwnerIndex=1728|OwnerPartId=1|FormalType=1|PinConglomerate=58|PinLength=30|Location.X=490|Location.Y=438|Name=13|Designator=A-13|PinPropagationDelay=0.000000E+000
|RECORD=2|OwnerIndex=1728|OwnerPartId=1|FormalType=1|PinConglomerate=56|PinLength=30|Location.X=550|Location.Y=438|Name=14|Designator=A-14|PinPropagationDelay=0.000000E+000
|RECORD=2|OwnerIndex=1728|OwnerPartId=1|FormalType=1|PinConglomerate=58|PinLength=30|Location.X=490|Location.Y=428|Name=15|Designator=A-15|PinPropagationDelay=0.000000E+000
|RECORD=2|OwnerIndex=1728|OwnerPartId=1|FormalType=1|PinConglomerate=56|PinLength=30|Location.X=550|Location.Y=428|Name=16|Designator=A-16|PinPropagationDelay=0.000000E+000
|RECORD=2|OwnerIndex=1728|OwnerPartId=1|FormalType=1|PinConglomerate=58|PinLength=30|Location.X=490|Location.Y=418|Name=17|Designator=A-17|PinPropagationDelay=0.000000E+000
|RECORD=2|OwnerIndex=1728|OwnerPartId=1|FormalType=1|PinConglomerate=56|PinLength=30|Location.X=550|Location.Y=418|Name=18|Designator=A-18|PinPropagationDelay=0.000000E+000
|RECORD=2|OwnerIndex=1728|OwnerPartId=1|FormalType=1|PinConglomerate=58|PinLength=30|Location.X=490|Location.Y=408|Name=19|Designator=A-19|PinPropagationDelay=0.000000E+000
|RECORD=2|OwnerIndex=1728|OwnerPartId=1|FormalType=1|PinConglomerate=56|PinLength=30|Location.X=550|Location.Y=408|Name=20|Designator=A-20|PinPropagationDelay=0.000000E+000
|RECORD=2|OwnerIndex=1728|OwnerPartId=1|FormalType=1|PinConglomerate=58|PinLength=30|Location.X=490|Location.Y=398|Name=21|Designator=A-21|PinPropagationDelay=0.000000E+000
|RECORD=2|OwnerIndex=1728|OwnerPartId=1|FormalType=1|PinConglomerate=56|PinLength=30|Location.X=550|Location.Y=398|Name=22|Designator=A-22|PinPropagationDelay=0.000000E+000
|RECORD=2|OwnerIndex=1728|OwnerPartId=1|FormalType=1|PinConglomerate=58|PinLength=30|Location.X=490|Location.Y=388|Name=23|Designator=A-23|PinPropagationDelay=0.000000E+000
|RECORD=2|OwnerIndex=1728|OwnerPartId=1|FormalType=1|PinConglomerate=56|PinLength=30|Location.X=550|Location.Y=388|Name=24|Designator=A-24|PinPropagationDelay=0.000000E+000
|RECORD=2|OwnerIndex=1728|OwnerPartId=1|FormalType=1|PinConglomerate=58|PinLength=30|Location.X=490|Location.Y=378|Name=25|Designator=A-25|PinPropagationDelay=0.000000E+000
|RECORD=2|OwnerIndex=1728|OwnerPartId=1|FormalType=1|PinConglomerate=56|PinLength=30|Location.X=550|Location.Y=378|Name=26|Designator=A-26|PinPropagationDelay=0.000000E+000
|RECORD=2|OwnerIndex=1728|OwnerPartId=1|FormalType=1|PinConglomerate=58|PinLength=30|Location.X=490|Location.Y=368|Name=27|Designator=A-27|PinPropagationDelay=0.000000E+000
|RECORD=2|OwnerIndex=1728|OwnerPartId=1|FormalType=1|PinConglomerate=56|PinLength=30|Location.X=550|Location.Y=368|Name=28|Designator=A-28|PinPropagationDelay=0.000000E+000
|RECORD=2|OwnerIndex=1728|OwnerPartId=1|FormalType=1|PinConglomerate=58|PinLength=30|Location.X=490|Location.Y=358|Name=29|Designator=A-29|PinPropagationDelay=0.000000E+000
|RECORD=2|OwnerIndex=1728|OwnerPartId=1|FormalType=1|PinConglomerate=56|PinLength=30|Location.X=550|Location.Y=358|Name=30|Designator=A-30|PinPropagationDelay=0.000000E+000
|RECORD=2|OwnerIndex=1728|OwnerPartId=1|FormalType=1|PinConglomerate=58|PinLength=30|Location.X=490|Location.Y=348|Name=31|Designator=A-31|PinPropagationDelay=0.000000E+000
|RECORD=2|OwnerIndex=1728|OwnerPartId=1|FormalType=1|PinConglomerate=56|PinLength=30|Location.X=550|Location.Y=348|Name=32|Designator=A-32|PinPropagationDelay=0.000000E+000
|RECORD=2|OwnerIndex=1728|OwnerPartId=1|FormalType=1|PinConglomerate=58|PinLength=30|Location.X=490|Location.Y=338|Name=33|Designator=A-33|PinPropagationDelay=0.000000E+000
|RECORD=2|OwnerIndex=1728|OwnerPartId=1|FormalType=1|PinConglomerate=56|PinLength=30|Location.X=550|Location.Y=338|Name=34|Designator=A-34|PinPropagationDelay=0.000000E+000
|RECORD=2|OwnerIndex=1728|OwnerPartId=1|FormalType=1|PinConglomerate=58|PinLength=30|Location.X=490|Location.Y=328|Name=35|Designator=A-35|PinPropagationDelay=0.000000E+000
|RECORD=2|OwnerIndex=1728|OwnerPartId=1|FormalType=1|PinConglomerate=56|PinLength=30|Location.X=550|Location.Y=328|Name=36|Designator=A-36|PinPropagationDelay=0.000000E+000
|RECORD=2|OwnerIndex=1728|OwnerPartId=1|FormalType=1|PinConglomerate=58|PinLength=30|Location.X=490|Location.Y=318|Name=37|Designator=A-37|PinPropagationDelay=0.000000E+000
|RECORD=2|OwnerIndex=1728|OwnerPartId=1|FormalType=1|PinConglomerate=56|PinLength=30|Location.X=550|Location.Y=318|Name=38|Designator=A-38|PinPropagationDelay=0.000000E+000
|RECORD=2|OwnerIndex=1728|OwnerPartId=1|FormalType=1|PinConglomerate=58|PinLength=30|Location.X=490|Location.Y=308|Name=39|Designator=A-39|PinPropagationDelay=0.000000E+000
|RECORD=2|OwnerIndex=1728|OwnerPartId=1|FormalType=1|PinConglomerate=56|PinLength=30|Location.X=550|Location.Y=308|Name=40|Designator=A-40|PinPropagationDelay=0.000000E+000
|RECORD=2|OwnerIndex=1728|OwnerPartId=1|FormalType=1|PinConglomerate=58|PinLength=30|Location.X=490|Location.Y=298|Name=41|Designator=A-41|PinPropagationDelay=0.000000E+000
|RECORD=2|OwnerIndex=1728|OwnerPartId=1|FormalType=1|PinConglomerate=56|PinLength=30|Location.X=550|Location.Y=298|Name=42|Designator=A-42|PinPropagationDelay=0.000000E+000
|RECORD=2|OwnerIndex=1728|OwnerPartId=1|FormalType=1|PinConglomerate=58|PinLength=30|Location.X=490|Location.Y=288|Name=43|Designator=A-43|PinPropagationDelay=0.000000E+000
|RECORD=2|OwnerIndex=1728|OwnerPartId=1|FormalType=1|PinConglomerate=56|PinLength=30|Location.X=550|Location.Y=288|Name=44|Designator=A-44|PinPropagationDelay=0.000000E+000
|RECORD=2|OwnerIndex=1728|OwnerPartId=1|FormalType=1|PinConglomerate=58|PinLength=30|Location.X=490|Location.Y=278|Name=45|Designator=A-45|PinPropagationDelay=0.000000E+000
|RECORD=2|OwnerIndex=1728|OwnerPartId=1|FormalType=1|PinConglomerate=56|PinLength=30|Location.X=550|Location.Y=278|Name=46|Designator=A-46|PinPropagationDelay=0.000000E+000
|RECORD=2|OwnerIndex=1728|OwnerPartId=1|FormalType=1|PinConglomerate=58|PinLength=30|Location.X=490|Location.Y=268|Name=47|Designator=A-47|PinPropagationDelay=0.000000E+000
|RECORD=2|OwnerIndex=1728|OwnerPartId=1|FormalType=1|PinConglomerate=56|PinLength=30|Location.X=550|Location.Y=268|Name=48|Designator=A-48|PinPropagationDelay=0.000000E+000
|RECORD=2|OwnerIndex=1728|OwnerPartId=1|FormalType=1|PinConglomerate=58|PinLength=30|Location.X=490|Location.Y=258|Name=49|Designator=A-49|PinPropagationDelay=0.000000E+000
|RECORD=2|OwnerIndex=1728|OwnerPartId=1|FormalType=1|PinConglomerate=56|PinLength=30|Location.X=550|Location.Y=258|Name=50|Designator=A-50|PinPropagationDelay=0.000000E+000
|RECORD=2|OwnerIndex=1728|OwnerPartId=1|FormalType=1|PinConglomerate=58|PinLength=30|Location.X=490|Location.Y=248|Name=51|Designator=A-51|PinPropagationDelay=0.000000E+000
|RECORD=2|OwnerIndex=1728|OwnerPartId=1|FormalType=1|PinConglomerate=56|PinLength=30|Location.X=550|Location.Y=248|Name=52|Designator=A-52|PinPropagationDelay=0.000000E+000
|RECORD=2|OwnerIndex=1728|OwnerPartId=1|FormalType=1|PinConglomerate=58|PinLength=30|Location.X=490|Location.Y=238|Name=53|Designator=A-53|PinPropagationDelay=0.000000E+000
|RECORD=2|OwnerIndex=1728|OwnerPartId=1|FormalType=1|PinConglomerate=56|PinLength=30|Location.X=550|Location.Y=238|Name=54|Designator=A-54|PinPropagationDelay=0.000000E+000
|RECORD=2|OwnerIndex=1728|OwnerPartId=1|FormalType=1|PinConglomerate=58|PinLength=30|Location.X=490|Location.Y=228|Name=55|Designator=A-55|PinPropagationDelay=0.000000E+000
|RECORD=2|OwnerIndex=1728|OwnerPartId=1|FormalType=1|PinConglomerate=56|PinLength=30|Location.X=550|Location.Y=228|Name=56|Designator=A-56|PinPropagationDelay=0.000000E+000
|RECORD=2|OwnerIndex=1728|OwnerPartId=1|FormalType=1|PinConglomerate=58|PinLength=30|Location.X=490|Location.Y=218|Name=57|Designator=A-57|PinPropagationDelay=0.000000E+000
|RECORD=2|OwnerIndex=1728|OwnerPartId=1|FormalType=1|PinConglomerate=56|PinLength=30|Location.X=550|Location.Y=218|Name=58|Designator=A-58|PinPropagationDelay=0.000000E+000
|RECORD=2|OwnerIndex=1728|OwnerPartId=1|FormalType=1|PinConglomerate=58|PinLength=30|Location.X=490|Location.Y=208|Name=59|Designator=A-59|PinPropagationDelay=0.000000E+000
|RECORD=2|OwnerIndex=1728|OwnerPartId=1|FormalType=1|PinConglomerate=56|PinLength=30|Location.X=550|Location.Y=208|Name=60|Designator=A-60|PinPropagationDelay=0.000000E+000
|RECORD=2|OwnerIndex=1728|OwnerPartId=1|FormalType=1|PinConglomerate=58|PinLength=30|Location.X=490|Location.Y=198|Name=61|Designator=A-61|PinPropagationDelay=0.000000E+000
|RECORD=2|OwnerIndex=1728|OwnerPartId=1|FormalType=1|PinConglomerate=56|PinLength=30|Location.X=550|Location.Y=198|Name=62|Designator=A-62|PinPropagationDelay=0.000000E+000
|RECORD=2|OwnerIndex=1728|OwnerPartId=1|FormalType=1|PinConglomerate=58|PinLength=30|Location.X=490|Location.Y=188|Name=63|Designator=A-63|PinPropagationDelay=0.000000E+000
|RECORD=2|OwnerIndex=1728|OwnerPartId=1|FormalType=1|PinConglomerate=56|PinLength=30|Location.X=550|Location.Y=188|Name=64|Designator=A-64|PinPropagationDelay=0.000000E+000
|RECORD=2|OwnerIndex=1728|OwnerPartId=1|FormalType=1|PinConglomerate=58|PinLength=30|Location.X=490|Location.Y=178|Name=65|Designator=A-65|PinPropagationDelay=0.000000E+000
|RECORD=2|OwnerIndex=1728|OwnerPartId=1|FormalType=1|PinConglomerate=56|PinLength=30|Location.X=550|Location.Y=178|Name=66|Designator=A-66|PinPropagationDelay=0.000000E+000
|RECORD=2|OwnerIndex=1728|OwnerPartId=1|FormalType=1|PinConglomerate=58|PinLength=30|Location.X=490|Location.Y=168|Name=67|Designator=A-67|PinPropagationDelay=0.000000E+000
|RECORD=2|OwnerIndex=1728|OwnerPartId=1|FormalType=1|PinConglomerate=56|PinLength=30|Location.X=550|Location.Y=168|Name=68|Designator=A-68|PinPropagationDelay=0.000000E+000
|RECORD=2|OwnerIndex=1728|OwnerPartId=1|FormalType=1|PinConglomerate=58|PinLength=30|Location.X=490|Location.Y=158|Name=69|Designator=A-69|PinPropagationDelay=0.000000E+000
|RECORD=2|OwnerIndex=1728|OwnerPartId=1|FormalType=1|PinConglomerate=56|PinLength=30|Location.X=550|Location.Y=158|Name=70|Designator=A-70|PinPropagationDelay=0.000000E+000
|RECORD=2|OwnerIndex=1728|OwnerPartId=1|FormalType=1|PinConglomerate=58|PinLength=30|Location.X=490|Location.Y=148|Name=71|Designator=A-71|PinPropagationDelay=0.000000E+000
|RECORD=2|OwnerIndex=1728|OwnerPartId=1|FormalType=1|PinConglomerate=56|PinLength=30|Location.X=550|Location.Y=148|Name=72|Designator=A-72|PinPropagationDelay=0.000000E+000
|RECORD=2|OwnerIndex=1728|OwnerPartId=1|FormalType=1|PinConglomerate=58|PinLength=30|Location.X=490|Location.Y=138|Name=73|Designator=A-73|PinPropagationDelay=0.000000E+000
|RECORD=2|OwnerIndex=1728|OwnerPartId=1|FormalType=1|PinConglomerate=56|PinLength=30|Location.X=550|Location.Y=138|Name=74|Designator=A-74|PinPropagationDelay=0.000000E+000
|RECORD=2|OwnerIndex=1728|OwnerPartId=1|FormalType=1|PinConglomerate=58|PinLength=30|Location.X=490|Location.Y=128|Name=75|Designator=A-75|PinPropagationDelay=0.000000E+000
|RECORD=2|OwnerIndex=1728|OwnerPartId=1|FormalType=1|PinConglomerate=56|PinLength=30|Location.X=550|Location.Y=128|Name=76|Designator=A-76|PinPropagationDelay=0.000000E+000
|RECORD=2|OwnerIndex=1728|OwnerPartId=1|FormalType=1|PinConglomerate=58|PinLength=30|Location.X=490|Location.Y=118|Name=77|Designator=A-77|PinPropagationDelay=0.000000E+000
|RECORD=2|OwnerIndex=1728|OwnerPartId=1|FormalType=1|PinConglomerate=56|PinLength=30|Location.X=550|Location.Y=118|Name=78|Designator=A-78|PinPropagationDelay=0.000000E+000
|RECORD=2|OwnerIndex=1728|OwnerPartId=1|FormalType=1|PinConglomerate=58|PinLength=30|Location.X=490|Location.Y=108|Name=79|Designator=A-79|PinPropagationDelay=0.000000E+000
|RECORD=2|OwnerIndex=1728|OwnerPartId=1|FormalType=1|PinConglomerate=56|PinLength=30|Location.X=550|Location.Y=108|Name=80|Designator=A-80|PinPropagationDelay=0.000000E+000
|RECORD=2|OwnerIndex=1728|OwnerPartId=1|FormalType=1|PinConglomerate=58|PinLength=30|Location.X=490|Location.Y=98|Name=81|Designator=A-81|PinPropagationDelay=0.000000E+000
|RECORD=2|OwnerIndex=1728|OwnerPartId=1|FormalType=1|PinConglomerate=56|PinLength=30|Location.X=550|Location.Y=98|Name=82|Designator=A-82|PinPropagationDelay=0.000000E+000
|RECORD=2|OwnerIndex=1728|OwnerPartId=1|FormalType=1|PinConglomerate=58|PinLength=30|Location.X=490|Location.Y=88|Name=83|Designator=A-83|PinPropagationDelay=0.000000E+000
|RECORD=2|OwnerIndex=1728|OwnerPartId=1|FormalType=1|PinConglomerate=56|PinLength=30|Location.X=550|Location.Y=88|Name=84|Designator=A-84|PinPropagationDelay=0.000000E+000
|RECORD=34|OwnerIndex=1728|IndexInSheet=-1|OwnerPartId=-1|Location.X=490|Location.Y=508|Color=8388608|FontID=1|Text=P1|Name=Designator|ReadOnlyState=1
|RECORD=41|OwnerIndex=1728|IndexInSheet=-1|OwnerPartId=-1|Location.X=490|Location.Y=68|Color=8388608|FontID=1|Text=FPGA_CONN|Name=Comment
|RECORD=44|OwnerIndex=1728
|RECORD=45|OwnerIndex=2407|IndexInSheet=-1|ModelName=FPGA_CONN|ModelType=PCBLIB|DatafileCount=1|ModelDatafileEntity0=FPGA_CONN|ModelDatafileKind0=PCBLib|IsCurrent=T
|RECORD=46|OwnerIndex=2408
|RECORD=48|OwnerIndex=2408
|RECORD=1|LibReference=FPGA_CONN|PartCount=5|DisplayModeCount=1|IndexInSheet=336|OwnerPartId=-1|Location.X=1160|Location.Y=498|CurrentPartId=4|LibraryPath=*|SourceLibraryName=FPGA_CONN.SchLib|TargetFileName=*|AreaColor=11599871|Color=128|PartIDLocked=T|NotUseDBTableName=T|DesignItemId=FPGA_CONN|AllPinCount=336
|RECORD=14|OwnerIndex=2411|IsNotAccesible=T|OwnerPartId=2|Location.X=1190|Location.Y=78|Corner.X=1250|Corner.Y=508|Color=128|AreaColor=11599871|IsSolid=T
|RECORD=2|OwnerIndex=2411|OwnerPartId=2|FormalType=1|PinConglomerate=58|PinLength=30|Location.X=1190|Location.Y=498|Name=1|Designator=B-1|PinPropagationDelay=0.000000E+000
|RECORD=2|OwnerIndex=2411|OwnerPartId=2|FormalType=1|PinConglomerate=56|PinLength=30|Location.X=1250|Location.Y=498|Name=2|Designator=B-2|PinPropagationDelay=0.000000E+000
|RECORD=2|OwnerIndex=2411|OwnerPartId=2|FormalType=1|PinConglomerate=58|PinLength=30|Location.X=1190|Location.Y=488|Name=3|Designator=B-3|PinPropagationDelay=0.000000E+000
|RECORD=2|OwnerIndex=2411|OwnerPartId=2|FormalType=1|PinConglomerate=56|PinLength=30|Location.X=1250|Location.Y=488|Name=4|Designator=B-4|PinPropagationDelay=0.000000E+000
|RECORD=2|OwnerIndex=2411|OwnerPartId=2|FormalType=1|PinConglomerate=58|PinLength=30|Location.X=1190|Location.Y=478|Name=5|Designator=B-5|PinPropagationDelay=0.000000E+000
|RECORD=2|OwnerIndex=2411|OwnerPartId=2|FormalType=1|PinConglomerate=56|PinLength=30|Location.X=1250|Location.Y=478|Name=6|Designator=B-6|PinPropagationDelay=0.000000E+000
|RECORD=2|OwnerIndex=2411|OwnerPartId=2|FormalType=1|PinConglomerate=58|PinLength=30|Location.X=1190|Location.Y=468|Name=7|Designator=B-7|PinPropagationDelay=0.000000E+000
|RECORD=2|OwnerIndex=2411|OwnerPartId=2|FormalType=1|PinConglomerate=56|PinLength=30|Location.X=1250|Location.Y=468|Name=8|Designator=B-8|PinPropagationDelay=0.000000E+000
|RECORD=2|OwnerIndex=2411|OwnerPartId=2|FormalType=1|PinConglomerate=58|PinLength=30|Location.X=1190|Location.Y=458|Name=9|Designator=B-9|PinPropagationDelay=0.000000E+000
|RECORD=2|OwnerIndex=2411|OwnerPartId=2|FormalType=1|PinConglomerate=56|PinLength=30|Location.X=1250|Location.Y=458|Name=10|Designator=B-10|PinPropagationDelay=0.000000E+000
|RECORD=2|OwnerIndex=2411|OwnerPartId=2|FormalType=1|PinConglomerate=58|PinLength=30|Location.X=1190|Location.Y=448|Name=11|Designator=B-11|PinPropagationDelay=0.000000E+000
|RECORD=2|OwnerIndex=2411|OwnerPartId=2|FormalType=1|PinConglomerate=56|PinLength=30|Location.X=1250|Location.Y=448|Name=12|Designator=B-12|PinPropagationDelay=0.000000E+000
|RECORD=2|OwnerIndex=2411|OwnerPartId=2|FormalType=1|PinConglomerate=58|PinLength=30|Location.X=1190|Location.Y=438|Name=13|Designator=B-13|PinPropagationDelay=0.000000E+000
|RECORD=2|OwnerIndex=2411|OwnerPartId=2|FormalType=1|PinConglomerate=56|PinLength=30|Location.X=1250|Location.Y=438|Name=14|Designator=B-14|PinPropagationDelay=0.000000E+000
|RECORD=2|OwnerIndex=2411|OwnerPartId=2|FormalType=1|PinConglomerate=58|PinLength=30|Location.X=1190|Location.Y=428|Name=15|Designator=B-15|PinPropagationDelay=0.000000E+000
|RECORD=2|OwnerIndex=2411|OwnerPartId=2|FormalType=1|PinConglomerate=56|PinLength=30|Location.X=1250|Location.Y=428|Name=16|Designator=B-16|PinPropagationDelay=0.000000E+000
|RECORD=2|OwnerIndex=2411|OwnerPartId=2|FormalType=1|PinConglomerate=58|PinLength=30|Location.X=1190|Location.Y=418|Name=17|Designator=B-17|PinPropagationDelay=0.000000E+000
|RECORD=2|OwnerIndex=2411|OwnerPartId=2|FormalType=1|PinConglomerate=56|PinLength=30|Location.X=1250|Location.Y=418|Name=18|Designator=B-18|PinPropagationDelay=0.000000E+000
|RECORD=2|OwnerIndex=2411|OwnerPartId=2|FormalType=1|PinConglomerate=58|PinLength=30|Location.X=1190|Location.Y=408|Name=19|Designator=B-19|PinPropagationDelay=0.000000E+000
|RECORD=2|OwnerIndex=2411|OwnerPartId=2|FormalType=1|PinConglomerate=56|PinLength=30|Location.X=1250|Location.Y=408|Name=20|Designator=B-20|PinPropagationDelay=0.000000E+000
|RECORD=2|OwnerIndex=2411|OwnerPartId=2|FormalType=1|PinConglomerate=58|PinLength=30|Location.X=1190|Location.Y=398|Name=21|Designator=B-21|PinPropagationDelay=0.000000E+000
|RECORD=2|OwnerIndex=2411|OwnerPartId=2|FormalType=1|PinConglomerate=56|PinLength=30|Location.X=1250|Location.Y=398|Name=22|Designator=B-22|PinPropagationDelay=0.000000E+000
|RECORD=2|OwnerIndex=2411|OwnerPartId=2|FormalType=1|PinConglomerate=58|PinLength=30|Location.X=1190|Location.Y=388|Name=23|Designator=B-23|PinPropagationDelay=0.000000E+000
|RECORD=2|OwnerIndex=2411|OwnerPartId=2|FormalType=1|PinConglomerate=56|PinLength=30|Location.X=1250|Location.Y=388|Name=24|Designator=B-24|PinPropagationDelay=0.000000E+000
|RECORD=2|OwnerIndex=2411|OwnerPartId=2|FormalType=1|PinConglomerate=58|PinLength=30|Location.X=1190|Location.Y=378|Name=25|Designator=B-25|PinPropagationDelay=0.000000E+000
|RECORD=2|OwnerIndex=2411|OwnerPartId=2|FormalType=1|PinConglomerate=56|PinLength=30|Location.X=1250|Location.Y=378|Name=26|Designator=B-26|PinPropagationDelay=0.000000E+000
|RECORD=2|OwnerIndex=2411|OwnerPartId=2|FormalType=1|PinConglomerate=58|PinLength=30|Location.X=1190|Location.Y=368|Name=27|Designator=B-27|PinPropagationDelay=0.000000E+000
|RECORD=2|OwnerIndex=2411|OwnerPartId=2|FormalType=1|PinConglomerate=56|PinLength=30|Location.X=1250|Location.Y=368|Name=28|Designator=B-28|PinPropagationDelay=0.000000E+000
|RECORD=2|OwnerIndex=2411|OwnerPartId=2|FormalType=1|PinConglomerate=58|PinLength=30|Location.X=1190|Location.Y=358|Name=29|Designator=B-29|PinPropagationDelay=0.000000E+000
|RECORD=2|OwnerIndex=2411|OwnerPartId=2|FormalType=1|PinConglomerate=56|PinLength=30|Location.X=1250|Location.Y=358|Name=30|Designator=B-30|PinPropagationDelay=0.000000E+000
|RECORD=2|OwnerIndex=2411|OwnerPartId=2|FormalType=1|PinConglomerate=58|PinLength=30|Location.X=1190|Location.Y=348|Name=31|Designator=B-31|PinPropagationDelay=0.000000E+000
|RECORD=2|OwnerIndex=2411|OwnerPartId=2|FormalType=1|PinConglomerate=56|PinLength=30|Location.X=1250|Location.Y=348|Name=32|Designator=B-32|PinPropagationDelay=0.000000E+000
|RECORD=2|OwnerIndex=2411|OwnerPartId=2|FormalType=1|PinConglomerate=58|PinLength=30|Location.X=1190|Location.Y=338|Name=33|Designator=B-33|PinPropagationDelay=0.000000E+000
|RECORD=2|OwnerIndex=2411|OwnerPartId=2|FormalType=1|PinConglomerate=56|PinLength=30|Location.X=1250|Location.Y=338|Name=34|Designator=B-34|PinPropagationDelay=0.000000E+000
|RECORD=2|OwnerIndex=2411|OwnerPartId=2|FormalType=1|PinConglomerate=58|PinLength=30|Location.X=1190|Location.Y=328|Name=35|Designator=B-35|PinPropagationDelay=0.000000E+000
|RECORD=2|OwnerIndex=2411|OwnerPartId=2|FormalType=1|PinConglomerate=56|PinLength=30|Location.X=1250|Location.Y=328|Name=36|Designator=B-36|PinPropagationDelay=0.000000E+000
|RECORD=2|OwnerIndex=2411|OwnerPartId=2|FormalType=1|PinConglomerate=58|PinLength=30|Location.X=1190|Location.Y=318|Name=37|Designator=B-37|PinPropagationDelay=0.000000E+000
|RECORD=2|OwnerIndex=2411|OwnerPartId=2|FormalType=1|PinConglomerate=56|PinLength=30|Location.X=1250|Location.Y=318|Name=38|Designator=B-38|PinPropagationDelay=0.000000E+000
|RECORD=2|OwnerIndex=2411|OwnerPartId=2|FormalType=1|PinConglomerate=58|PinLength=30|Location.X=1190|Location.Y=308|Name=39|Designator=B-39|PinPropagationDelay=0.000000E+000
|RECORD=2|OwnerIndex=2411|OwnerPartId=2|FormalType=1|PinConglomerate=56|PinLength=30|Location.X=1250|Location.Y=308|Name=40|Designator=B-40|PinPropagationDelay=0.000000E+000
|RECORD=2|OwnerIndex=2411|OwnerPartId=2|FormalType=1|PinConglomerate=58|PinLength=30|Location.X=1190|Location.Y=298|Name=41|Designator=B-41|PinPropagationDelay=0.000000E+000
|RECORD=2|OwnerIndex=2411|OwnerPartId=2|FormalType=1|PinConglomerate=56|PinLength=30|Location.X=1250|Location.Y=298|Name=42|Designator=B-42|PinPropagationDelay=0.000000E+000
|RECORD=2|OwnerIndex=2411|OwnerPartId=2|FormalType=1|PinConglomerate=58|PinLength=30|Location.X=1190|Location.Y=288|Name=43|Designator=B-43|PinPropagationDelay=0.000000E+000
|RECORD=2|OwnerIndex=2411|OwnerPartId=2|FormalType=1|PinConglomerate=56|PinLength=30|Location.X=1250|Location.Y=288|Name=44|Designator=B-44|PinPropagationDelay=0.000000E+000
|RECORD=2|OwnerIndex=2411|OwnerPartId=2|FormalType=1|PinConglomerate=58|PinLength=30|Location.X=1190|Location.Y=278|Name=45|Designator=B-45|PinPropagationDelay=0.000000E+000
|RECORD=2|OwnerIndex=2411|OwnerPartId=2|FormalType=1|PinConglomerate=56|PinLength=30|Location.X=1250|Location.Y=278|Name=46|Designator=B-46|PinPropagationDelay=0.000000E+000
|RECORD=2|OwnerIndex=2411|OwnerPartId=2|FormalType=1|PinConglomerate=58|PinLength=30|Location.X=1190|Location.Y=268|Name=47|Designator=B-47|PinPropagationDelay=0.000000E+000
|RECORD=2|OwnerIndex=2411|OwnerPartId=2|FormalType=1|PinConglomerate=56|PinLength=30|Location.X=1250|Location.Y=268|Name=48|Designator=B-48|PinPropagationDelay=0.000000E+000
|RECORD=2|OwnerIndex=2411|OwnerPartId=2|FormalType=1|PinConglomerate=58|PinLength=30|Location.X=1190|Location.Y=258|Name=49|Designator=B-49|PinPropagationDelay=0.000000E+000
|RECORD=2|OwnerIndex=2411|OwnerPartId=2|FormalType=1|PinConglomerate=56|PinLength=30|Location.X=1250|Location.Y=258|Name=50|Designator=B-50|PinPropagationDelay=0.000000E+000
|RECORD=2|OwnerIndex=2411|OwnerPartId=2|FormalType=1|PinConglomerate=58|PinLength=30|Location.X=1190|Location.Y=248|Name=51|Designator=B-51|PinPropagationDelay=0.000000E+000
|RECORD=2|OwnerIndex=2411|OwnerPartId=2|FormalType=1|PinConglomerate=56|PinLength=30|Location.X=1250|Location.Y=248|Name=52|Designator=B-52|PinPropagationDelay=0.000000E+000
|RECORD=2|OwnerIndex=2411|OwnerPartId=2|FormalType=1|PinConglomerate=58|PinLength=30|Location.X=1190|Location.Y=238|Name=53|Designator=B-53|PinPropagationDelay=0.000000E+000
|RECORD=2|OwnerIndex=2411|OwnerPartId=2|FormalType=1|PinConglomerate=56|PinLength=30|Location.X=1250|Location.Y=238|Name=54|Designator=B-54|PinPropagationDelay=0.000000E+000
|RECORD=2|OwnerIndex=2411|OwnerPartId=2|FormalType=1|PinConglomerate=58|PinLength=30|Location.X=1190|Location.Y=228|Name=55|Designator=B-55|PinPropagationDelay=0.000000E+000
|RECORD=2|OwnerIndex=2411|OwnerPartId=2|FormalType=1|PinConglomerate=56|PinLength=30|Location.X=1250|Location.Y=228|Name=56|Designator=B-56|PinPropagationDelay=0.000000E+000
|RECORD=2|OwnerIndex=2411|OwnerPartId=2|FormalType=1|PinConglomerate=58|PinLength=30|Location.X=1190|Location.Y=218|Name=57|Designator=B-57|PinPropagationDelay=0.000000E+000
|RECORD=2|OwnerIndex=2411|OwnerPartId=2|FormalType=1|PinConglomerate=56|PinLength=30|Location.X=1250|Location.Y=218|Name=58|Designator=B-58|PinPropagationDelay=0.000000E+000
|RECORD=2|OwnerIndex=2411|OwnerPartId=2|FormalType=1|PinConglomerate=58|PinLength=30|Location.X=1190|Location.Y=208|Name=59|Designator=B-59|PinPropagationDelay=0.000000E+000
|RECORD=2|OwnerIndex=2411|OwnerPartId=2|FormalType=1|PinConglomerate=56|PinLength=30|Location.X=1250|Location.Y=208|Name=60|Designator=B-60|PinPropagationDelay=0.000000E+000
|RECORD=2|OwnerIndex=2411|OwnerPartId=2|FormalType=1|PinConglomerate=58|PinLength=30|Location.X=1190|Location.Y=198|Name=61|Designator=B-61|PinPropagationDelay=0.000000E+000
|RECORD=2|OwnerIndex=2411|OwnerPartId=2|FormalType=1|PinConglomerate=56|PinLength=30|Location.X=1250|Location.Y=198|Name=62|Designator=B-62|PinPropagationDelay=0.000000E+000
|RECORD=2|OwnerIndex=2411|OwnerPartId=2|FormalType=1|PinConglomerate=58|PinLength=30|Location.X=1190|Location.Y=188|Name=63|Designator=B-63|PinPropagationDelay=0.000000E+000
|RECORD=2|OwnerIndex=2411|OwnerPartId=2|FormalType=1|PinConglomerate=56|PinLength=30|Location.X=1250|Location.Y=188|Name=64|Designator=B-64|PinPropagationDelay=0.000000E+000
|RECORD=2|OwnerIndex=2411|OwnerPartId=2|FormalType=1|PinConglomerate=58|PinLength=30|Location.X=1190|Location.Y=178|Name=65|Designator=B-65|PinPropagationDelay=0.000000E+000
|RECORD=2|OwnerIndex=2411|OwnerPartId=2|FormalType=1|PinConglomerate=56|PinLength=30|Location.X=1250|Location.Y=178|Name=66|Designator=B-66|PinPropagationDelay=0.000000E+000
|RECORD=2|OwnerIndex=2411|OwnerPartId=2|FormalType=1|PinConglomerate=58|PinLength=30|Location.X=1190|Location.Y=168|Name=67|Designator=B-67|PinPropagationDelay=0.000000E+000
|RECORD=2|OwnerIndex=2411|OwnerPartId=2|FormalType=1|PinConglomerate=56|PinLength=30|Location.X=1250|Location.Y=168|Name=68|Designator=B-68|PinPropagationDelay=0.000000E+000
|RECORD=2|OwnerIndex=2411|OwnerPartId=2|FormalType=1|PinConglomerate=58|PinLength=30|Location.X=1190|Location.Y=158|Name=69|Designator=B-69|PinPropagationDelay=0.000000E+000
|RECORD=2|OwnerIndex=2411|OwnerPartId=2|FormalType=1|PinConglomerate=56|PinLength=30|Location.X=1250|Location.Y=158|Name=70|Designator=B-70|PinPropagationDelay=0.000000E+000
|RECORD=2|OwnerIndex=2411|OwnerPartId=2|FormalType=1|PinConglomerate=58|PinLength=30|Location.X=1190|Location.Y=148|Name=71|Designator=B-71|PinPropagationDelay=0.000000E+000
|RECORD=2|OwnerIndex=2411|OwnerPartId=2|FormalType=1|PinConglomerate=56|PinLength=30|Location.X=1250|Location.Y=148|Name=72|Designator=B-72|PinPropagationDelay=0.000000E+000
|RECORD=2|OwnerIndex=2411|OwnerPartId=2|FormalType=1|PinConglomerate=58|PinLength=30|Location.X=1190|Location.Y=138|Name=73|Designator=B-73|PinPropagationDelay=0.000000E+000
|RECORD=2|OwnerIndex=2411|OwnerPartId=2|FormalType=1|PinConglomerate=56|PinLength=30|Location.X=1250|Location.Y=138|Name=74|Designator=B-74|PinPropagationDelay=0.000000E+000
|RECORD=2|OwnerIndex=2411|OwnerPartId=2|FormalType=1|PinConglomerate=58|PinLength=30|Location.X=1190|Location.Y=128|Name=75|Designator=B-75|PinPropagationDelay=0.000000E+000
|RECORD=2|OwnerIndex=2411|OwnerPartId=2|FormalType=1|PinConglomerate=56|PinLength=30|Location.X=1250|Location.Y=128|Name=76|Designator=B-76|PinPropagationDelay=0.000000E+000
|RECORD=2|OwnerIndex=2411|OwnerPartId=2|FormalType=1|PinConglomerate=58|PinLength=30|Location.X=1190|Location.Y=118|Name=77|Designator=B-77|PinPropagationDelay=0.000000E+000
|RECORD=2|OwnerIndex=2411|OwnerPartId=2|FormalType=1|PinConglomerate=56|PinLength=30|Location.X=1250|Location.Y=118|Name=78|Designator=B-78|PinPropagationDelay=0.000000E+000
|RECORD=2|OwnerIndex=2411|OwnerPartId=2|FormalType=1|PinConglomerate=58|PinLength=30|Location.X=1190|Location.Y=108|Name=79|Designator=B-79|PinPropagationDelay=0.000000E+000
|RECORD=2|OwnerIndex=2411|OwnerPartId=2|FormalType=1|PinConglomerate=56|PinLength=30|Location.X=1250|Location.Y=108|Name=80|Designator=B-80|PinPropagationDelay=0.000000E+000
|RECORD=2|OwnerIndex=2411|OwnerPartId=2|FormalType=1|PinConglomerate=58|PinLength=30|Location.X=1190|Location.Y=98|Name=81|Designator=B-81|PinPropagationDelay=0.000000E+000
|RECORD=2|OwnerIndex=2411|OwnerPartId=2|FormalType=1|PinConglomerate=56|PinLength=30|Location.X=1250|Location.Y=98|Name=82|Designator=B-82|PinPropagationDelay=0.000000E+000
|RECORD=2|OwnerIndex=2411|OwnerPartId=2|FormalType=1|PinConglomerate=58|PinLength=30|Location.X=1190|Location.Y=88|Name=83|Designator=B-83|PinPropagationDelay=0.000000E+000
|RECORD=2|OwnerIndex=2411|OwnerPartId=2|FormalType=1|PinConglomerate=56|PinLength=30|Location.X=1250|Location.Y=88|Name=84|Designator=B-84|PinPropagationDelay=0.000000E+000
|RECORD=14|OwnerIndex=2411|IsNotAccesible=T|IndexInSheet=85|OwnerPartId=3|Location.X=1190|Location.Y=78|Corner.X=1250|Corner.Y=508|Color=128|AreaColor=11599871|IsSolid=T
|RECORD=2|OwnerIndex=2411|OwnerPartId=3|FormalType=1|PinConglomerate=58|PinLength=30|Location.X=1190|Location.Y=498|Name=1|Designator=C-1|PinPropagationDelay=0.000000E+000
|RECORD=2|OwnerIndex=2411|OwnerPartId=3|FormalType=1|PinConglomerate=56|PinLength=30|Location.X=1250|Location.Y=498|Name=2|Designator=C-2|PinPropagationDelay=0.000000E+000
|RECORD=2|OwnerIndex=2411|OwnerPartId=3|FormalType=1|PinConglomerate=58|PinLength=30|Location.X=1190|Location.Y=488|Name=3|Designator=C-3|PinPropagationDelay=0.000000E+000
|RECORD=2|OwnerIndex=2411|OwnerPartId=3|FormalType=1|PinConglomerate=56|PinLength=30|Location.X=1250|Location.Y=488|Name=4|Designator=C-4|PinPropagationDelay=0.000000E+000
|RECORD=2|OwnerIndex=2411|OwnerPartId=3|FormalType=1|PinConglomerate=58|PinLength=30|Location.X=1190|Location.Y=478|Name=5|Designator=C-5|PinPropagationDelay=0.000000E+000
|RECORD=2|OwnerIndex=2411|OwnerPartId=3|FormalType=1|PinConglomerate=56|PinLength=30|Location.X=1250|Location.Y=478|Name=6|Designator=C-6|PinPropagationDelay=0.000000E+000
|RECORD=2|OwnerIndex=2411|OwnerPartId=3|FormalType=1|PinConglomerate=58|PinLength=30|Location.X=1190|Location.Y=468|Name=7|Designator=C-7|PinPropagationDelay=0.000000E+000
|RECORD=2|OwnerIndex=2411|OwnerPartId=3|FormalType=1|PinConglomerate=56|PinLength=30|Location.X=1250|Location.Y=468|Name=8|Designator=C-8|PinPropagationDelay=0.000000E+000
|RECORD=2|OwnerIndex=2411|OwnerPartId=3|FormalType=1|PinConglomerate=58|PinLength=30|Location.X=1190|Location.Y=458|Name=9|Designator=C-9|PinPropagationDelay=0.000000E+000
|RECORD=2|OwnerIndex=2411|OwnerPartId=3|FormalType=1|PinConglomerate=56|PinLength=30|Location.X=1250|Location.Y=458|Name=10|Designator=C-10|PinPropagationDelay=0.000000E+000
|RECORD=2|OwnerIndex=2411|OwnerPartId=3|FormalType=1|PinConglomerate=58|PinLength=30|Location.X=1190|Location.Y=448|Name=11|Designator=C-11|PinPropagationDelay=0.000000E+000
|RECORD=2|OwnerIndex=2411|OwnerPartId=3|FormalType=1|PinConglomerate=56|PinLength=30|Location.X=1250|Location.Y=448|Name=12|Designator=C-12|PinPropagationDelay=0.000000E+000
|RECORD=2|OwnerIndex=2411|OwnerPartId=3|FormalType=1|PinConglomerate=58|PinLength=30|Location.X=1190|Location.Y=438|Name=13|Designator=C-13|PinPropagationDelay=0.000000E+000
|RECORD=2|OwnerIndex=2411|OwnerPartId=3|FormalType=1|PinConglomerate=56|PinLength=30|Location.X=1250|Location.Y=438|Name=14|Designator=C-14|PinPropagationDelay=0.000000E+000
|RECORD=2|OwnerIndex=2411|OwnerPartId=3|FormalType=1|PinConglomerate=58|PinLength=30|Location.X=1190|Location.Y=428|Name=15|Designator=C-15|PinPropagationDelay=0.000000E+000
|RECORD=2|OwnerIndex=2411|OwnerPartId=3|FormalType=1|PinConglomerate=56|PinLength=30|Location.X=1250|Location.Y=428|Name=16|Designator=C-16|PinPropagationDelay=0.000000E+000
|RECORD=2|OwnerIndex=2411|OwnerPartId=3|FormalType=1|PinConglomerate=58|PinLength=30|Location.X=1190|Location.Y=418|Name=17|Designator=C-17|PinPropagationDelay=0.000000E+000
|RECORD=2|OwnerIndex=2411|OwnerPartId=3|FormalType=1|PinConglomerate=56|PinLength=30|Location.X=1250|Location.Y=418|Name=18|Designator=C-18|PinPropagationDelay=0.000000E+000
|RECORD=2|OwnerIndex=2411|OwnerPartId=3|FormalType=1|PinConglomerate=58|PinLength=30|Location.X=1190|Location.Y=408|Name=19|Designator=C-19|PinPropagationDelay=0.000000E+000
|RECORD=2|OwnerIndex=2411|OwnerPartId=3|FormalType=1|PinConglomerate=56|PinLength=30|Location.X=1250|Location.Y=408|Name=20|Designator=C-20|PinPropagationDelay=0.000000E+000
|RECORD=2|OwnerIndex=2411|OwnerPartId=3|FormalType=1|PinConglomerate=58|PinLength=30|Location.X=1190|Location.Y=398|Name=21|Designator=C-21|PinPropagationDelay=0.000000E+000
|RECORD=2|OwnerIndex=2411|OwnerPartId=3|FormalType=1|PinConglomerate=56|PinLength=30|Location.X=1250|Location.Y=398|Name=22|Designator=C-22|PinPropagationDelay=0.000000E+000
|RECORD=2|OwnerIndex=2411|OwnerPartId=3|FormalType=1|PinConglomerate=58|PinLength=30|Location.X=1190|Location.Y=388|Name=23|Designator=C-23|PinPropagationDelay=0.000000E+000
|RECORD=2|OwnerIndex=2411|OwnerPartId=3|FormalType=1|PinConglomerate=56|PinLength=30|Location.X=1250|Location.Y=388|Name=24|Designator=C-24|PinPropagationDelay=0.000000E+000
|RECORD=2|OwnerIndex=2411|OwnerPartId=3|FormalType=1|PinConglomerate=58|PinLength=30|Location.X=1190|Location.Y=378|Name=25|Designator=C-25|PinPropagationDelay=0.000000E+000
|RECORD=2|OwnerIndex=2411|OwnerPartId=3|FormalType=1|PinConglomerate=56|PinLength=30|Location.X=1250|Location.Y=378|Name=26|Designator=C-26|PinPropagationDelay=0.000000E+000
|RECORD=2|OwnerIndex=2411|OwnerPartId=3|FormalType=1|PinConglomerate=58|PinLength=30|Location.X=1190|Location.Y=368|Name=27|Designator=C-27|PinPropagationDelay=0.000000E+000
|RECORD=2|OwnerIndex=2411|OwnerPartId=3|FormalType=1|PinConglomerate=56|PinLength=30|Location.X=1250|Location.Y=368|Name=28|Designator=C-28|PinPropagationDelay=0.000000E+000
|RECORD=2|OwnerIndex=2411|OwnerPartId=3|FormalType=1|PinConglomerate=58|PinLength=30|Location.X=1190|Location.Y=358|Name=29|Designator=C-29|PinPropagationDelay=0.000000E+000
|RECORD=2|OwnerIndex=2411|OwnerPartId=3|FormalType=1|PinConglomerate=56|PinLength=30|Location.X=1250|Location.Y=358|Name=30|Designator=C-30|PinPropagationDelay=0.000000E+000
|RECORD=2|OwnerIndex=2411|OwnerPartId=3|FormalType=1|PinConglomerate=58|PinLength=30|Location.X=1190|Location.Y=348|Name=31|Designator=C-31|PinPropagationDelay=0.000000E+000
|RECORD=2|OwnerIndex=2411|OwnerPartId=3|FormalType=1|PinConglomerate=56|PinLength=30|Location.X=1250|Location.Y=348|Name=32|Designator=C-32|PinPropagationDelay=0.000000E+000
|RECORD=2|OwnerIndex=2411|OwnerPartId=3|FormalType=1|PinConglomerate=58|PinLength=30|Location.X=1190|Location.Y=338|Name=33|Designator=C-33|PinPropagationDelay=0.000000E+000
|RECORD=2|OwnerIndex=2411|OwnerPartId=3|FormalType=1|PinConglomerate=56|PinLength=30|Location.X=1250|Location.Y=338|Name=34|Designator=C-34|PinPropagationDelay=0.000000E+000
|RECORD=2|OwnerIndex=2411|OwnerPartId=3|FormalType=1|PinConglomerate=58|PinLength=30|Location.X=1190|Location.Y=328|Name=35|Designator=C-35|PinPropagationDelay=0.000000E+000
|RECORD=2|OwnerIndex=2411|OwnerPartId=3|FormalType=1|PinConglomerate=56|PinLength=30|Location.X=1250|Location.Y=328|Name=36|Designator=C-36|PinPropagationDelay=0.000000E+000
|RECORD=2|OwnerIndex=2411|OwnerPartId=3|FormalType=1|PinConglomerate=58|PinLength=30|Location.X=1190|Location.Y=318|Name=37|Designator=C-37|PinPropagationDelay=0.000000E+000
|RECORD=2|OwnerIndex=2411|OwnerPartId=3|FormalType=1|PinConglomerate=56|PinLength=30|Location.X=1250|Location.Y=318|Name=38|Designator=C-38|PinPropagationDelay=0.000000E+000
|RECORD=2|OwnerIndex=2411|OwnerPartId=3|FormalType=1|PinConglomerate=58|PinLength=30|Location.X=1190|Location.Y=308|Name=39|Designator=C-39|PinPropagationDelay=0.000000E+000
|RECORD=2|OwnerIndex=2411|OwnerPartId=3|FormalType=1|PinConglomerate=56|PinLength=30|Location.X=1250|Location.Y=308|Name=40|Designator=C-40|PinPropagationDelay=0.000000E+000
|RECORD=2|OwnerIndex=2411|OwnerPartId=3|FormalType=1|PinConglomerate=58|PinLength=30|Location.X=1190|Location.Y=298|Name=41|Designator=C-41|PinPropagationDelay=0.000000E+000
|RECORD=2|OwnerIndex=2411|OwnerPartId=3|FormalType=1|PinConglomerate=56|PinLength=30|Location.X=1250|Location.Y=298|Name=42|Designator=C-42|PinPropagationDelay=0.000000E+000
|RECORD=2|OwnerIndex=2411|OwnerPartId=3|FormalType=1|PinConglomerate=58|PinLength=30|Location.X=1190|Location.Y=288|Name=43|Designator=C-43|PinPropagationDelay=0.000000E+000
|RECORD=2|OwnerIndex=2411|OwnerPartId=3|FormalType=1|PinConglomerate=56|PinLength=30|Location.X=1250|Location.Y=288|Name=44|Designator=C-44|PinPropagationDelay=0.000000E+000
|RECORD=2|OwnerIndex=2411|OwnerPartId=3|FormalType=1|PinConglomerate=58|PinLength=30|Location.X=1190|Location.Y=278|Name=45|Designator=C-45|PinPropagationDelay=0.000000E+000
|RECORD=2|OwnerIndex=2411|OwnerPartId=3|FormalType=1|PinConglomerate=56|PinLength=30|Location.X=1250|Location.Y=278|Name=46|Designator=C-46|PinPropagationDelay=0.000000E+000
|RECORD=2|OwnerIndex=2411|OwnerPartId=3|FormalType=1|PinConglomerate=58|PinLength=30|Location.X=1190|Location.Y=268|Name=47|Designator=C-47|PinPropagationDelay=0.000000E+000
|RECORD=2|OwnerIndex=2411|OwnerPartId=3|FormalType=1|PinConglomerate=56|PinLength=30|Location.X=1250|Location.Y=268|Name=48|Designator=C-48|PinPropagationDelay=0.000000E+000
|RECORD=2|OwnerIndex=2411|OwnerPartId=3|FormalType=1|PinConglomerate=58|PinLength=30|Location.X=1190|Location.Y=258|Name=49|Designator=C-49|PinPropagationDelay=0.000000E+000
|RECORD=2|OwnerIndex=2411|OwnerPartId=3|FormalType=1|PinConglomerate=56|PinLength=30|Location.X=1250|Location.Y=258|Name=50|Designator=C-50|PinPropagationDelay=0.000000E+000
|RECORD=2|OwnerIndex=2411|OwnerPartId=3|FormalType=1|PinConglomerate=58|PinLength=30|Location.X=1190|Location.Y=248|Name=51|Designator=C-51|PinPropagationDelay=0.000000E+000
|RECORD=2|OwnerIndex=2411|OwnerPartId=3|FormalType=1|PinConglomerate=56|PinLength=30|Location.X=1250|Location.Y=248|Name=52|Designator=C-52|PinPropagationDelay=0.000000E+000
|RECORD=2|OwnerIndex=2411|OwnerPartId=3|FormalType=1|PinConglomerate=58|PinLength=30|Location.X=1190|Location.Y=238|Name=53|Designator=C-53|PinPropagationDelay=0.000000E+000
|RECORD=2|OwnerIndex=2411|OwnerPartId=3|FormalType=1|PinConglomerate=56|PinLength=30|Location.X=1250|Location.Y=238|Name=54|Designator=C-54|PinPropagationDelay=0.000000E+000
|RECORD=2|OwnerIndex=2411|OwnerPartId=3|FormalType=1|PinConglomerate=58|PinLength=30|Location.X=1190|Location.Y=228|Name=55|Designator=C-55|PinPropagationDelay=0.000000E+000
|RECORD=2|OwnerIndex=2411|OwnerPartId=3|FormalType=1|PinConglomerate=56|PinLength=30|Location.X=1250|Location.Y=228|Name=56|Designator=C-56|PinPropagationDelay=0.000000E+000
|RECORD=2|OwnerIndex=2411|OwnerPartId=3|FormalType=1|PinConglomerate=58|PinLength=30|Location.X=1190|Location.Y=218|Name=57|Designator=C-57|PinPropagationDelay=0.000000E+000
|RECORD=2|OwnerIndex=2411|OwnerPartId=3|FormalType=1|PinConglomerate=56|PinLength=30|Location.X=1250|Location.Y=218|Name=58|Designator=C-58|PinPropagationDelay=0.000000E+000
|RECORD=2|OwnerIndex=2411|OwnerPartId=3|FormalType=1|PinConglomerate=58|PinLength=30|Location.X=1190|Location.Y=208|Name=59|Designator=C-59|PinPropagationDelay=0.000000E+000
|RECORD=2|OwnerIndex=2411|OwnerPartId=3|FormalType=1|PinConglomerate=56|PinLength=30|Location.X=1250|Location.Y=208|Name=60|Designator=C-60|PinPropagationDelay=0.000000E+000
|RECORD=2|OwnerIndex=2411|OwnerPartId=3|FormalType=1|PinConglomerate=58|PinLength=30|Location.X=1190|Location.Y=198|Name=61|Designator=C-61|PinPropagationDelay=0.000000E+000
|RECORD=2|OwnerIndex=2411|OwnerPartId=3|FormalType=1|PinConglomerate=56|PinLength=30|Location.X=1250|Location.Y=198|Name=62|Designator=C-62|PinPropagationDelay=0.000000E+000
|RECORD=2|OwnerIndex=2411|OwnerPartId=3|FormalType=1|PinConglomerate=58|PinLength=30|Location.X=1190|Location.Y=188|Name=63|Designator=C-63|PinPropagationDelay=0.000000E+000
|RECORD=2|OwnerIndex=2411|OwnerPartId=3|FormalType=1|PinConglomerate=56|PinLength=30|Location.X=1250|Location.Y=188|Name=64|Designator=C-64|PinPropagationDelay=0.000000E+000
|RECORD=2|OwnerIndex=2411|OwnerPartId=3|FormalType=1|PinConglomerate=58|PinLength=30|Location.X=1190|Location.Y=178|Name=65|Designator=C-65|PinPropagationDelay=0.000000E+000
|RECORD=2|OwnerIndex=2411|OwnerPartId=3|FormalType=1|PinConglomerate=56|PinLength=30|Location.X=1250|Location.Y=178|Name=66|Designator=C-66|PinPropagationDelay=0.000000E+000
|RECORD=2|OwnerIndex=2411|OwnerPartId=3|FormalType=1|PinConglomerate=58|PinLength=30|Location.X=1190|Location.Y=168|Name=67|Designator=C-67|PinPropagationDelay=0.000000E+000
|RECORD=2|OwnerIndex=2411|OwnerPartId=3|FormalType=1|PinConglomerate=56|PinLength=30|Location.X=1250|Location.Y=168|Name=68|Designator=C-68|PinPropagationDelay=0.000000E+000
|RECORD=2|OwnerIndex=2411|OwnerPartId=3|FormalType=1|PinConglomerate=58|PinLength=30|Location.X=1190|Location.Y=158|Name=69|Designator=C-69|PinPropagationDelay=0.000000E+000
|RECORD=2|OwnerIndex=2411|OwnerPartId=3|FormalType=1|PinConglomerate=56|PinLength=30|Location.X=1250|Location.Y=158|Name=70|Designator=C-70|PinPropagationDelay=0.000000E+000
|RECORD=2|OwnerIndex=2411|OwnerPartId=3|FormalType=1|PinConglomerate=58|PinLength=30|Location.X=1190|Location.Y=148|Name=71|Designator=C-71|PinPropagationDelay=0.000000E+000
|RECORD=2|OwnerIndex=2411|OwnerPartId=3|FormalType=1|PinConglomerate=56|PinLength=30|Location.X=1250|Location.Y=148|Name=72|Designator=C-72|PinPropagationDelay=0.000000E+000
|RECORD=2|OwnerIndex=2411|OwnerPartId=3|FormalType=1|PinConglomerate=58|PinLength=30|Location.X=1190|Location.Y=138|Name=73|Designator=C-73|PinPropagationDelay=0.000000E+000
|RECORD=2|OwnerIndex=2411|OwnerPartId=3|FormalType=1|PinConglomerate=56|PinLength=30|Location.X=1250|Location.Y=138|Name=74|Designator=C-74|PinPropagationDelay=0.000000E+000
|RECORD=2|OwnerIndex=2411|OwnerPartId=3|FormalType=1|PinConglomerate=58|PinLength=30|Location.X=1190|Location.Y=128|Name=75|Designator=C-75|PinPropagationDelay=0.000000E+000
|RECORD=2|OwnerIndex=2411|OwnerPartId=3|FormalType=1|PinConglomerate=56|PinLength=30|Location.X=1250|Location.Y=128|Name=76|Designator=C-76|PinPropagationDelay=0.000000E+000
|RECORD=2|OwnerIndex=2411|OwnerPartId=3|FormalType=1|PinConglomerate=58|PinLength=30|Location.X=1190|Location.Y=118|Name=77|Designator=C-77|PinPropagationDelay=0.000000E+000
|RECORD=2|OwnerIndex=2411|OwnerPartId=3|FormalType=1|PinConglomerate=56|PinLength=30|Location.X=1250|Location.Y=118|Name=78|Designator=C-78|PinPropagationDelay=0.000000E+000
|RECORD=2|OwnerIndex=2411|OwnerPartId=3|FormalType=1|PinConglomerate=58|PinLength=30|Location.X=1190|Location.Y=108|Name=79|Designator=C-79|PinPropagationDelay=0.000000E+000
|RECORD=2|OwnerIndex=2411|OwnerPartId=3|FormalType=1|PinConglomerate=56|PinLength=30|Location.X=1250|Location.Y=108|Name=80|Designator=C-80|PinPropagationDelay=0.000000E+000
|RECORD=2|OwnerIndex=2411|OwnerPartId=3|FormalType=1|PinConglomerate=58|PinLength=30|Location.X=1190|Location.Y=98|Name=81|Designator=C-81|PinPropagationDelay=0.000000E+000
|RECORD=2|OwnerIndex=2411|OwnerPartId=3|FormalType=1|PinConglomerate=56|PinLength=30|Location.X=1250|Location.Y=98|Name=82|Designator=C-82|PinPropagationDelay=0.000000E+000
|RECORD=2|OwnerIndex=2411|OwnerPartId=3|FormalType=1|PinConglomerate=58|PinLength=30|Location.X=1190|Location.Y=88|Name=83|Designator=C-83|PinPropagationDelay=0.000000E+000
|RECORD=2|OwnerIndex=2411|OwnerPartId=3|FormalType=1|PinConglomerate=56|PinLength=30|Location.X=1250|Location.Y=88|Name=84|Designator=C-84|PinPropagationDelay=0.000000E+000
|RECORD=14|OwnerIndex=2411|IsNotAccesible=T|IndexInSheet=170|OwnerPartId=4|Location.X=1190|Location.Y=78|Corner.X=1250|Corner.Y=508|Color=128|AreaColor=11599871|IsSolid=T
|RECORD=2|OwnerIndex=2411|OwnerPartId=4|FormalType=1|PinConglomerate=58|PinLength=30|Location.X=1190|Location.Y=498|Name=1|Designator=D-1|PinPropagationDelay=0.000000E+000
|RECORD=2|OwnerIndex=2411|OwnerPartId=4|FormalType=1|PinConglomerate=56|PinLength=30|Location.X=1250|Location.Y=498|Name=2|Designator=D-2|PinPropagationDelay=0.000000E+000
|RECORD=2|OwnerIndex=2411|OwnerPartId=4|FormalType=1|PinConglomerate=58|PinLength=30|Location.X=1190|Location.Y=488|Name=3|Designator=D-3|PinPropagationDelay=0.000000E+000
|RECORD=2|OwnerIndex=2411|OwnerPartId=4|FormalType=1|PinConglomerate=56|PinLength=30|Location.X=1250|Location.Y=488|Name=4|Designator=D-4|PinPropagationDelay=0.000000E+000
|RECORD=2|OwnerIndex=2411|OwnerPartId=4|FormalType=1|PinConglomerate=58|PinLength=30|Location.X=1190|Location.Y=478|Name=5|Designator=D-5|PinPropagationDelay=0.000000E+000
|RECORD=2|OwnerIndex=2411|OwnerPartId=4|FormalType=1|PinConglomerate=56|PinLength=30|Location.X=1250|Location.Y=478|Name=6|Designator=D-6|PinPropagationDelay=0.000000E+000
|RECORD=2|OwnerIndex=2411|OwnerPartId=4|FormalType=1|PinConglomerate=58|PinLength=30|Location.X=1190|Location.Y=468|Name=7|Designator=D-7|PinPropagationDelay=0.000000E+000
|RECORD=2|OwnerIndex=2411|OwnerPartId=4|FormalType=1|PinConglomerate=56|PinLength=30|Location.X=1250|Location.Y=468|Name=8|Designator=D-8|PinPropagationDelay=0.000000E+000
|RECORD=2|OwnerIndex=2411|OwnerPartId=4|FormalType=1|PinConglomerate=58|PinLength=30|Location.X=1190|Location.Y=458|Name=9|Designator=D-9|PinPropagationDelay=0.000000E+000
|RECORD=2|OwnerIndex=2411|OwnerPartId=4|FormalType=1|PinConglomerate=56|PinLength=30|Location.X=1250|Location.Y=458|Name=10|Designator=D-10|PinPropagationDelay=0.000000E+000
|RECORD=2|OwnerIndex=2411|OwnerPartId=4|FormalType=1|PinConglomerate=58|PinLength=30|Location.X=1190|Location.Y=448|Name=11|Designator=D-11|PinPropagationDelay=0.000000E+000
|RECORD=2|OwnerIndex=2411|OwnerPartId=4|FormalType=1|PinConglomerate=56|PinLength=30|Location.X=1250|Location.Y=448|Name=12|Designator=D-12|PinPropagationDelay=0.000000E+000
|RECORD=2|OwnerIndex=2411|OwnerPartId=4|FormalType=1|PinConglomerate=58|PinLength=30|Location.X=1190|Location.Y=438|Name=13|Designator=D-13|PinPropagationDelay=0.000000E+000
|RECORD=2|OwnerIndex=2411|OwnerPartId=4|FormalType=1|PinConglomerate=56|PinLength=30|Location.X=1250|Location.Y=438|Name=14|Designator=D-14|PinPropagationDelay=0.000000E+000
|RECORD=2|OwnerIndex=2411|OwnerPartId=4|FormalType=1|PinConglomerate=58|PinLength=30|Location.X=1190|Location.Y=428|Name=15|Designator=D-15|PinPropagationDelay=0.000000E+000
|RECORD=2|OwnerIndex=2411|OwnerPartId=4|FormalType=1|PinConglomerate=56|PinLength=30|Location.X=1250|Location.Y=428|Name=16|Designator=D-16|PinPropagationDelay=0.000000E+000
|RECORD=2|OwnerIndex=2411|OwnerPartId=4|FormalType=1|PinConglomerate=58|PinLength=30|Location.X=1190|Location.Y=418|Name=17|Designator=D-17|PinPropagationDelay=0.000000E+000
|RECORD=2|OwnerIndex=2411|OwnerPartId=4|FormalType=1|PinConglomerate=56|PinLength=30|Location.X=1250|Location.Y=418|Name=18|Designator=D-18|PinPropagationDelay=0.000000E+000
|RECORD=2|OwnerIndex=2411|OwnerPartId=4|FormalType=1|PinConglomerate=58|PinLength=30|Location.X=1190|Location.Y=408|Name=19|Designator=D-19|PinPropagationDelay=0.000000E+000
|RECORD=2|OwnerIndex=2411|OwnerPartId=4|FormalType=1|PinConglomerate=56|PinLength=30|Location.X=1250|Location.Y=408|Name=20|Designator=D-20|PinPropagationDelay=0.000000E+000
|RECORD=2|OwnerIndex=2411|OwnerPartId=4|FormalType=1|PinConglomerate=58|PinLength=30|Location.X=1190|Location.Y=398|Name=21|Designator=D-21|PinPropagationDelay=0.000000E+000
|RECORD=2|OwnerIndex=2411|OwnerPartId=4|FormalType=1|PinConglomerate=56|PinLength=30|Location.X=1250|Location.Y=398|Name=22|Designator=D-22|PinPropagationDelay=0.000000E+000
|RECORD=2|OwnerIndex=2411|OwnerPartId=4|FormalType=1|PinConglomerate=58|PinLength=30|Location.X=1190|Location.Y=388|Name=23|Designator=D-23|PinPropagationDelay=0.000000E+000
|RECORD=2|OwnerIndex=2411|OwnerPartId=4|FormalType=1|PinConglomerate=56|PinLength=30|Location.X=1250|Location.Y=388|Name=24|Designator=D-24|PinPropagationDelay=0.000000E+000
|RECORD=2|OwnerIndex=2411|OwnerPartId=4|FormalType=1|PinConglomerate=58|PinLength=30|Location.X=1190|Location.Y=378|Name=25|Designator=D-25|PinPropagationDelay=0.000000E+000
|RECORD=2|OwnerIndex=2411|OwnerPartId=4|FormalType=1|PinConglomerate=56|PinLength=30|Location.X=1250|Location.Y=378|Name=26|Designator=D-26|PinPropagationDelay=0.000000E+000
|RECORD=2|OwnerIndex=2411|OwnerPartId=4|FormalType=1|PinConglomerate=58|PinLength=30|Location.X=1190|Location.Y=368|Name=27|Designator=D-27|PinPropagationDelay=0.000000E+000
|RECORD=2|OwnerIndex=2411|OwnerPartId=4|FormalType=1|PinConglomerate=56|PinLength=30|Location.X=1250|Location.Y=368|Name=28|Designator=D-28|PinPropagationDelay=0.000000E+000
|RECORD=2|OwnerIndex=2411|OwnerPartId=4|FormalType=1|PinConglomerate=58|PinLength=30|Location.X=1190|Location.Y=358|Name=29|Designator=D-29|PinPropagationDelay=0.000000E+000
|RECORD=2|OwnerIndex=2411|OwnerPartId=4|FormalType=1|PinConglomerate=56|PinLength=30|Location.X=1250|Location.Y=358|Name=30|Designator=D-30|PinPropagationDelay=0.000000E+000
|RECORD=2|OwnerIndex=2411|OwnerPartId=4|FormalType=1|PinConglomerate=58|PinLength=30|Location.X=1190|Location.Y=348|Name=31|Designator=D-31|PinPropagationDelay=0.000000E+000
|RECORD=2|OwnerIndex=2411|OwnerPartId=4|FormalType=1|PinConglomerate=56|PinLength=30|Location.X=1250|Location.Y=348|Name=32|Designator=D-32|PinPropagationDelay=0.000000E+000
|RECORD=2|OwnerIndex=2411|OwnerPartId=4|FormalType=1|PinConglomerate=58|PinLength=30|Location.X=1190|Location.Y=338|Name=33|Designator=D-33|PinPropagationDelay=0.000000E+000
|RECORD=2|OwnerIndex=2411|OwnerPartId=4|FormalType=1|PinConglomerate=56|PinLength=30|Location.X=1250|Location.Y=338|Name=34|Designator=D-34|PinPropagationDelay=0.000000E+000
|RECORD=2|OwnerIndex=2411|OwnerPartId=4|FormalType=1|PinConglomerate=58|PinLength=30|Location.X=1190|Location.Y=328|Name=35|Designator=D-35|PinPropagationDelay=0.000000E+000
|RECORD=2|OwnerIndex=2411|OwnerPartId=4|FormalType=1|PinConglomerate=56|PinLength=30|Location.X=1250|Location.Y=328|Name=36|Designator=D-36|PinPropagationDelay=0.000000E+000
|RECORD=2|OwnerIndex=2411|OwnerPartId=4|FormalType=1|PinConglomerate=58|PinLength=30|Location.X=1190|Location.Y=318|Name=37|Designator=D-37|PinPropagationDelay=0.000000E+000
|RECORD=2|OwnerIndex=2411|OwnerPartId=4|FormalType=1|PinConglomerate=56|PinLength=30|Location.X=1250|Location.Y=318|Name=38|Designator=D-38|PinPropagationDelay=0.000000E+000
|RECORD=2|OwnerIndex=2411|OwnerPartId=4|FormalType=1|PinConglomerate=58|PinLength=30|Location.X=1190|Location.Y=308|Name=39|Designator=D-39|PinPropagationDelay=0.000000E+000
|RECORD=2|OwnerIndex=2411|OwnerPartId=4|FormalType=1|PinConglomerate=56|PinLength=30|Location.X=1250|Location.Y=308|Name=40|Designator=D-40|PinPropagationDelay=0.000000E+000
|RECORD=2|OwnerIndex=2411|OwnerPartId=4|FormalType=1|PinConglomerate=58|PinLength=30|Location.X=1190|Location.Y=298|Name=41|Designator=D-41|PinPropagationDelay=0.000000E+000
|RECORD=2|OwnerIndex=2411|OwnerPartId=4|FormalType=1|PinConglomerate=56|PinLength=30|Location.X=1250|Location.Y=298|Name=42|Designator=D-42|PinPropagationDelay=0.000000E+000
|RECORD=2|OwnerIndex=2411|OwnerPartId=4|FormalType=1|PinConglomerate=58|PinLength=30|Location.X=1190|Location.Y=288|Name=43|Designator=D-43|PinPropagationDelay=0.000000E+000
|RECORD=2|OwnerIndex=2411|OwnerPartId=4|FormalType=1|PinConglomerate=56|PinLength=30|Location.X=1250|Location.Y=288|Name=44|Designator=D-44|PinPropagationDelay=0.000000E+000
|RECORD=2|OwnerIndex=2411|OwnerPartId=4|FormalType=1|PinConglomerate=58|PinLength=30|Location.X=1190|Location.Y=278|Name=45|Designator=D-45|PinPropagationDelay=0.000000E+000
|RECORD=2|OwnerIndex=2411|OwnerPartId=4|FormalType=1|PinConglomerate=56|PinLength=30|Location.X=1250|Location.Y=278|Name=46|Designator=D-46|PinPropagationDelay=0.000000E+000
|RECORD=2|OwnerIndex=2411|OwnerPartId=4|FormalType=1|PinConglomerate=58|PinLength=30|Location.X=1190|Location.Y=268|Name=47|Designator=D-47|PinPropagationDelay=0.000000E+000
|RECORD=2|OwnerIndex=2411|OwnerPartId=4|FormalType=1|PinConglomerate=56|PinLength=30|Location.X=1250|Location.Y=268|Name=48|Designator=D-48|PinPropagationDelay=0.000000E+000
|RECORD=2|OwnerIndex=2411|OwnerPartId=4|FormalType=1|PinConglomerate=58|PinLength=30|Location.X=1190|Location.Y=258|Name=49|Designator=D-49|PinPropagationDelay=0.000000E+000
|RECORD=2|OwnerIndex=2411|OwnerPartId=4|FormalType=1|PinConglomerate=56|PinLength=30|Location.X=1250|Location.Y=258|Name=50|Designator=D-50|PinPropagationDelay=0.000000E+000
|RECORD=2|OwnerIndex=2411|OwnerPartId=4|FormalType=1|PinConglomerate=58|PinLength=30|Location.X=1190|Location.Y=248|Name=51|Designator=D-51|PinPropagationDelay=0.000000E+000
|RECORD=2|OwnerIndex=2411|OwnerPartId=4|FormalType=1|PinConglomerate=56|PinLength=30|Location.X=1250|Location.Y=248|Name=52|Designator=D-52|PinPropagationDelay=0.000000E+000
|RECORD=2|OwnerIndex=2411|OwnerPartId=4|FormalType=1|PinConglomerate=58|PinLength=30|Location.X=1190|Location.Y=238|Name=53|Designator=D-53|PinPropagationDelay=0.000000E+000
|RECORD=2|OwnerIndex=2411|OwnerPartId=4|FormalType=1|PinConglomerate=56|PinLength=30|Location.X=1250|Location.Y=238|Name=54|Designator=D-54|PinPropagationDelay=0.000000E+000
|RECORD=2|OwnerIndex=2411|OwnerPartId=4|FormalType=1|PinConglomerate=58|PinLength=30|Location.X=1190|Location.Y=228|Name=55|Designator=D-55|PinPropagationDelay=0.000000E+000
|RECORD=2|OwnerIndex=2411|OwnerPartId=4|FormalType=1|PinConglomerate=56|PinLength=30|Location.X=1250|Location.Y=228|Name=56|Designator=D-56|PinPropagationDelay=0.000000E+000
|RECORD=2|OwnerIndex=2411|OwnerPartId=4|FormalType=1|PinConglomerate=58|PinLength=30|Location.X=1190|Location.Y=218|Name=57|Designator=D-57|PinPropagationDelay=0.000000E+000
|RECORD=2|OwnerIndex=2411|OwnerPartId=4|FormalType=1|PinConglomerate=56|PinLength=30|Location.X=1250|Location.Y=218|Name=58|Designator=D-58|PinPropagationDelay=0.000000E+000
|RECORD=2|OwnerIndex=2411|OwnerPartId=4|FormalType=1|PinConglomerate=58|PinLength=30|Location.X=1190|Location.Y=208|Name=59|Designator=D-59|PinPropagationDelay=0.000000E+000
|RECORD=2|OwnerIndex=2411|OwnerPartId=4|FormalType=1|PinConglomerate=56|PinLength=30|Location.X=1250|Location.Y=208|Name=60|Designator=D-60|PinPropagationDelay=0.000000E+000
|RECORD=2|OwnerIndex=2411|OwnerPartId=4|FormalType=1|PinConglomerate=58|PinLength=30|Location.X=1190|Location.Y=198|Name=61|Designator=D-61|PinPropagationDelay=0.000000E+000
|RECORD=2|OwnerIndex=2411|OwnerPartId=4|FormalType=1|PinConglomerate=56|PinLength=30|Location.X=1250|Location.Y=198|Name=62|Designator=D-62|PinPropagationDelay=0.000000E+000
|RECORD=2|OwnerIndex=2411|OwnerPartId=4|FormalType=1|PinConglomerate=58|PinLength=30|Location.X=1190|Location.Y=188|Name=63|Designator=D-63|PinPropagationDelay=0.000000E+000
|RECORD=2|OwnerIndex=2411|OwnerPartId=4|FormalType=1|PinConglomerate=56|PinLength=30|Location.X=1250|Location.Y=188|Name=64|Designator=D-64|PinPropagationDelay=0.000000E+000
|RECORD=2|OwnerIndex=2411|OwnerPartId=4|FormalType=1|PinConglomerate=58|PinLength=30|Location.X=1190|Location.Y=178|Name=65|Designator=D-65|PinPropagationDelay=0.000000E+000
|RECORD=2|OwnerIndex=2411|OwnerPartId=4|FormalType=1|PinConglomerate=56|PinLength=30|Location.X=1250|Location.Y=178|Name=66|Designator=D-66|PinPropagationDelay=0.000000E+000
|RECORD=2|OwnerIndex=2411|OwnerPartId=4|FormalType=1|PinConglomerate=58|PinLength=30|Location.X=1190|Location.Y=168|Name=67|Designator=D-67|PinPropagationDelay=0.000000E+000
|RECORD=2|OwnerIndex=2411|OwnerPartId=4|FormalType=1|PinConglomerate=56|PinLength=30|Location.X=1250|Location.Y=168|Name=68|Designator=D-68|PinPropagationDelay=0.000000E+000
|RECORD=2|OwnerIndex=2411|OwnerPartId=4|FormalType=1|PinConglomerate=58|PinLength=30|Location.X=1190|Location.Y=158|Name=69|Designator=D-69|PinPropagationDelay=0.000000E+000
|RECORD=2|OwnerIndex=2411|OwnerPartId=4|FormalType=1|PinConglomerate=56|PinLength=30|Location.X=1250|Location.Y=158|Name=70|Designator=D-70|PinPropagationDelay=0.000000E+000
|RECORD=2|OwnerIndex=2411|OwnerPartId=4|FormalType=1|PinConglomerate=58|PinLength=30|Location.X=1190|Location.Y=148|Name=71|Designator=D-71|PinPropagationDelay=0.000000E+000
|RECORD=2|OwnerIndex=2411|OwnerPartId=4|FormalType=1|PinConglomerate=56|PinLength=30|Location.X=1250|Location.Y=148|Name=72|Designator=D-72|PinPropagationDelay=0.000000E+000
|RECORD=2|OwnerIndex=2411|OwnerPartId=4|FormalType=1|PinConglomerate=58|PinLength=30|Location.X=1190|Location.Y=138|Name=73|Designator=D-73|PinPropagationDelay=0.000000E+000
|RECORD=2|OwnerIndex=2411|OwnerPartId=4|FormalType=1|PinConglomerate=56|PinLength=30|Location.X=1250|Location.Y=138|Name=74|Designator=D-74|PinPropagationDelay=0.000000E+000
|RECORD=2|OwnerIndex=2411|OwnerPartId=4|FormalType=1|PinConglomerate=58|PinLength=30|Location.X=1190|Location.Y=128|Name=75|Designator=D-75|PinPropagationDelay=0.000000E+000
|RECORD=2|OwnerIndex=2411|OwnerPartId=4|FormalType=1|PinConglomerate=56|PinLength=30|Location.X=1250|Location.Y=128|Name=76|Designator=D-76|PinPropagationDelay=0.000000E+000
|RECORD=2|OwnerIndex=2411|OwnerPartId=4|FormalType=1|PinConglomerate=58|PinLength=30|Location.X=1190|Location.Y=118|Name=77|Designator=D-77|PinPropagationDelay=0.000000E+000
|RECORD=2|OwnerIndex=2411|OwnerPartId=4|FormalType=1|PinConglomerate=56|PinLength=30|Location.X=1250|Location.Y=118|Name=78|Designator=D-78|PinPropagationDelay=0.000000E+000
|RECORD=2|OwnerIndex=2411|OwnerPartId=4|FormalType=1|PinConglomerate=58|PinLength=30|Location.X=1190|Location.Y=108|Name=79|Designator=D-79|PinPropagationDelay=0.000000E+000
|RECORD=2|OwnerIndex=2411|OwnerPartId=4|FormalType=1|PinConglomerate=56|PinLength=30|Location.X=1250|Location.Y=108|Name=80|Designator=D-80|PinPropagationDelay=0.000000E+000
|RECORD=2|OwnerIndex=2411|OwnerPartId=4|FormalType=1|PinConglomerate=58|PinLength=30|Location.X=1190|Location.Y=98|Name=81|Designator=D-81|PinPropagationDelay=0.000000E+000
|RECORD=2|OwnerIndex=2411|OwnerPartId=4|FormalType=1|PinConglomerate=56|PinLength=30|Location.X=1250|Location.Y=98|Name=82|Designator=D-82|PinPropagationDelay=0.000000E+000
|RECORD=2|OwnerIndex=2411|OwnerPartId=4|FormalType=1|PinConglomerate=58|PinLength=30|Location.X=1190|Location.Y=88|Name=83|Designator=D-83|PinPropagationDelay=0.000000E+000
|RECORD=2|OwnerIndex=2411|OwnerPartId=4|FormalType=1|PinConglomerate=56|PinLength=30|Location.X=1250|Location.Y=88|Name=84|Designator=D-84|PinPropagationDelay=0.000000E+000
|RECORD=14|OwnerIndex=2411|IsNotAccesible=T|IndexInSheet=255|OwnerPartId=1|Location.X=1190|Location.Y=78|Corner.X=1250|Corner.Y=508|Color=128|AreaColor=11599871|IsSolid=T
|RECORD=2|OwnerIndex=2411|OwnerPartId=1|FormalType=1|PinConglomerate=58|PinLength=30|Location.X=1190|Location.Y=498|Name=1|Designator=A-1|PinPropagationDelay=0.000000E+000
|RECORD=2|OwnerIndex=2411|OwnerPartId=1|FormalType=1|PinConglomerate=56|PinLength=30|Location.X=1250|Location.Y=498|Name=2|Designator=A-2|PinPropagationDelay=0.000000E+000
|RECORD=2|OwnerIndex=2411|OwnerPartId=1|FormalType=1|PinConglomerate=58|PinLength=30|Location.X=1190|Location.Y=488|Name=3|Designator=A-3|PinPropagationDelay=0.000000E+000
|RECORD=2|OwnerIndex=2411|OwnerPartId=1|FormalType=1|PinConglomerate=56|PinLength=30|Location.X=1250|Location.Y=488|Name=4|Designator=A-4|PinPropagationDelay=0.000000E+000
|RECORD=2|OwnerIndex=2411|OwnerPartId=1|FormalType=1|PinConglomerate=58|PinLength=30|Location.X=1190|Location.Y=478|Name=5|Designator=A-5|PinPropagationDelay=0.000000E+000
|RECORD=2|OwnerIndex=2411|OwnerPartId=1|FormalType=1|PinConglomerate=56|PinLength=30|Location.X=1250|Location.Y=478|Name=6|Designator=A-6|PinPropagationDelay=0.000000E+000
|RECORD=2|OwnerIndex=2411|OwnerPartId=1|FormalType=1|PinConglomerate=58|PinLength=30|Location.X=1190|Location.Y=468|Name=7|Designator=A-7|PinPropagationDelay=0.000000E+000
|RECORD=2|OwnerIndex=2411|OwnerPartId=1|FormalType=1|PinConglomerate=56|PinLength=30|Location.X=1250|Location.Y=468|Name=8|Designator=A-8|PinPropagationDelay=0.000000E+000
|RECORD=2|OwnerIndex=2411|OwnerPartId=1|FormalType=1|PinConglomerate=58|PinLength=30|Location.X=1190|Location.Y=458|Name=9|Designator=A-9|PinPropagationDelay=0.000000E+000
|RECORD=2|OwnerIndex=2411|OwnerPartId=1|FormalType=1|PinConglomerate=56|PinLength=30|Location.X=1250|Location.Y=458|Name=10|Designator=A-10|PinPropagationDelay=0.000000E+000
|RECORD=2|OwnerIndex=2411|OwnerPartId=1|FormalType=1|PinConglomerate=58|PinLength=30|Location.X=1190|Location.Y=448|Name=11|Designator=A-11|PinPropagationDelay=0.000000E+000
|RECORD=2|OwnerIndex=2411|OwnerPartId=1|FormalType=1|PinConglomerate=56|PinLength=30|Location.X=1250|Location.Y=448|Name=12|Designator=A-12|PinPropagationDelay=0.000000E+000
|RECORD=2|OwnerIndex=2411|OwnerPartId=1|FormalType=1|PinConglomerate=58|PinLength=30|Location.X=1190|Location.Y=438|Name=13|Designator=A-13|PinPropagationDelay=0.000000E+000
|RECORD=2|OwnerIndex=2411|OwnerPartId=1|FormalType=1|PinConglomerate=56|PinLength=30|Location.X=1250|Location.Y=438|Name=14|Designator=A-14|PinPropagationDelay=0.000000E+000
|RECORD=2|OwnerIndex=2411|OwnerPartId=1|FormalType=1|PinConglomerate=58|PinLength=30|Location.X=1190|Location.Y=428|Name=15|Designator=A-15|PinPropagationDelay=0.000000E+000
|RECORD=2|OwnerIndex=2411|OwnerPartId=1|FormalType=1|PinConglomerate=56|PinLength=30|Location.X=1250|Location.Y=428|Name=16|Designator=A-16|PinPropagationDelay=0.000000E+000
|RECORD=2|OwnerIndex=2411|OwnerPartId=1|FormalType=1|PinConglomerate=58|PinLength=30|Location.X=1190|Location.Y=418|Name=17|Designator=A-17|PinPropagationDelay=0.000000E+000
|RECORD=2|OwnerIndex=2411|OwnerPartId=1|FormalType=1|PinConglomerate=56|PinLength=30|Location.X=1250|Location.Y=418|Name=18|Designator=A-18|PinPropagationDelay=0.000000E+000
|RECORD=2|OwnerIndex=2411|OwnerPartId=1|FormalType=1|PinConglomerate=58|PinLength=30|Location.X=1190|Location.Y=408|Name=19|Designator=A-19|PinPropagationDelay=0.000000E+000
|RECORD=2|OwnerIndex=2411|OwnerPartId=1|FormalType=1|PinConglomerate=56|PinLength=30|Location.X=1250|Location.Y=408|Name=20|Designator=A-20|PinPropagationDelay=0.000000E+000
|RECORD=2|OwnerIndex=2411|OwnerPartId=1|FormalType=1|PinConglomerate=58|PinLength=30|Location.X=1190|Location.Y=398|Name=21|Designator=A-21|PinPropagationDelay=0.000000E+000
|RECORD=2|OwnerIndex=2411|OwnerPartId=1|FormalType=1|PinConglomerate=56|PinLength=30|Location.X=1250|Location.Y=398|Name=22|Designator=A-22|PinPropagationDelay=0.000000E+000
|RECORD=2|OwnerIndex=2411|OwnerPartId=1|FormalType=1|PinConglomerate=58|PinLength=30|Location.X=1190|Location.Y=388|Name=23|Designator=A-23|PinPropagationDelay=0.000000E+000
|RECORD=2|OwnerIndex=2411|OwnerPartId=1|FormalType=1|PinConglomerate=56|PinLength=30|Location.X=1250|Location.Y=388|Name=24|Designator=A-24|PinPropagationDelay=0.000000E+000
|RECORD=2|OwnerIndex=2411|OwnerPartId=1|FormalType=1|PinConglomerate=58|PinLength=30|Location.X=1190|Location.Y=378|Name=25|Designator=A-25|PinPropagationDelay=0.000000E+000
|RECORD=2|OwnerIndex=2411|OwnerPartId=1|FormalType=1|PinConglomerate=56|PinLength=30|Location.X=1250|Location.Y=378|Name=26|Designator=A-26|PinPropagationDelay=0.000000E+000
|RECORD=2|OwnerIndex=2411|OwnerPartId=1|FormalType=1|PinConglomerate=58|PinLength=30|Location.X=1190|Location.Y=368|Name=27|Designator=A-27|PinPropagationDelay=0.000000E+000
|RECORD=2|OwnerIndex=2411|OwnerPartId=1|FormalType=1|PinConglomerate=56|PinLength=30|Location.X=1250|Location.Y=368|Name=28|Designator=A-28|PinPropagationDelay=0.000000E+000
|RECORD=2|OwnerIndex=2411|OwnerPartId=1|FormalType=1|PinConglomerate=58|PinLength=30|Location.X=1190|Location.Y=358|Name=29|Designator=A-29|PinPropagationDelay=0.000000E+000
|RECORD=2|OwnerIndex=2411|OwnerPartId=1|FormalType=1|PinConglomerate=56|PinLength=30|Location.X=1250|Location.Y=358|Name=30|Designator=A-30|PinPropagationDelay=0.000000E+000
|RECORD=2|OwnerIndex=2411|OwnerPartId=1|FormalType=1|PinConglomerate=58|PinLength=30|Location.X=1190|Location.Y=348|Name=31|Designator=A-31|PinPropagationDelay=0.000000E+000
|RECORD=2|OwnerIndex=2411|OwnerPartId=1|FormalType=1|PinConglomerate=56|PinLength=30|Location.X=1250|Location.Y=348|Name=32|Designator=A-32|PinPropagationDelay=0.000000E+000
|RECORD=2|OwnerIndex=2411|OwnerPartId=1|FormalType=1|PinConglomerate=58|PinLength=30|Location.X=1190|Location.Y=338|Name=33|Designator=A-33|PinPropagationDelay=0.000000E+000
|RECORD=2|OwnerIndex=2411|OwnerPartId=1|FormalType=1|PinConglomerate=56|PinLength=30|Location.X=1250|Location.Y=338|Name=34|Designator=A-34|PinPropagationDelay=0.000000E+000
|RECORD=2|OwnerIndex=2411|OwnerPartId=1|FormalType=1|PinConglomerate=58|PinLength=30|Location.X=1190|Location.Y=328|Name=35|Designator=A-35|PinPropagationDelay=0.000000E+000
|RECORD=2|OwnerIndex=2411|OwnerPartId=1|FormalType=1|PinConglomerate=56|PinLength=30|Location.X=1250|Location.Y=328|Name=36|Designator=A-36|PinPropagationDelay=0.000000E+000
|RECORD=2|OwnerIndex=2411|OwnerPartId=1|FormalType=1|PinConglomerate=58|PinLength=30|Location.X=1190|Location.Y=318|Name=37|Designator=A-37|PinPropagationDelay=0.000000E+000
|RECORD=2|OwnerIndex=2411|OwnerPartId=1|FormalType=1|PinConglomerate=56|PinLength=30|Location.X=1250|Location.Y=318|Name=38|Designator=A-38|PinPropagationDelay=0.000000E+000
|RECORD=2|OwnerIndex=2411|OwnerPartId=1|FormalType=1|PinConglomerate=58|PinLength=30|Location.X=1190|Location.Y=308|Name=39|Designator=A-39|PinPropagationDelay=0.000000E+000
|RECORD=2|OwnerIndex=2411|OwnerPartId=1|FormalType=1|PinConglomerate=56|PinLength=30|Location.X=1250|Location.Y=308|Name=40|Designator=A-40|PinPropagationDelay=0.000000E+000
|RECORD=2|OwnerIndex=2411|OwnerPartId=1|FormalType=1|PinConglomerate=58|PinLength=30|Location.X=1190|Location.Y=298|Name=41|Designator=A-41|PinPropagationDelay=0.000000E+000
|RECORD=2|OwnerIndex=2411|OwnerPartId=1|FormalType=1|PinConglomerate=56|PinLength=30|Location.X=1250|Location.Y=298|Name=42|Designator=A-42|PinPropagationDelay=0.000000E+000
|RECORD=2|OwnerIndex=2411|OwnerPartId=1|FormalType=1|PinConglomerate=58|PinLength=30|Location.X=1190|Location.Y=288|Name=43|Designator=A-43|PinPropagationDelay=0.000000E+000
|RECORD=2|OwnerIndex=2411|OwnerPartId=1|FormalType=1|PinConglomerate=56|PinLength=30|Location.X=1250|Location.Y=288|Name=44|Designator=A-44|PinPropagationDelay=0.000000E+000
|RECORD=2|OwnerIndex=2411|OwnerPartId=1|FormalType=1|PinConglomerate=58|PinLength=30|Location.X=1190|Location.Y=278|Name=45|Designator=A-45|PinPropagationDelay=0.000000E+000
|RECORD=2|OwnerIndex=2411|OwnerPartId=1|FormalType=1|PinConglomerate=56|PinLength=30|Location.X=1250|Location.Y=278|Name=46|Designator=A-46|PinPropagationDelay=0.000000E+000
|RECORD=2|OwnerIndex=2411|OwnerPartId=1|FormalType=1|PinConglomerate=58|PinLength=30|Location.X=1190|Location.Y=268|Name=47|Designator=A-47|PinPropagationDelay=0.000000E+000
|RECORD=2|OwnerIndex=2411|OwnerPartId=1|FormalType=1|PinConglomerate=56|PinLength=30|Location.X=1250|Location.Y=268|Name=48|Designator=A-48|PinPropagationDelay=0.000000E+000
|RECORD=2|OwnerIndex=2411|OwnerPartId=1|FormalType=1|PinConglomerate=58|PinLength=30|Location.X=1190|Location.Y=258|Name=49|Designator=A-49|PinPropagationDelay=0.000000E+000
|RECORD=2|OwnerIndex=2411|OwnerPartId=1|FormalType=1|PinConglomerate=56|PinLength=30|Location.X=1250|Location.Y=258|Name=50|Designator=A-50|PinPropagationDelay=0.000000E+000
|RECORD=2|OwnerIndex=2411|OwnerPartId=1|FormalType=1|PinConglomerate=58|PinLength=30|Location.X=1190|Location.Y=248|Name=51|Designator=A-51|PinPropagationDelay=0.000000E+000
|RECORD=2|OwnerIndex=2411|OwnerPartId=1|FormalType=1|PinConglomerate=56|PinLength=30|Location.X=1250|Location.Y=248|Name=52|Designator=A-52|PinPropagationDelay=0.000000E+000
|RECORD=2|OwnerIndex=2411|OwnerPartId=1|FormalType=1|PinConglomerate=58|PinLength=30|Location.X=1190|Location.Y=238|Name=53|Designator=A-53|PinPropagationDelay=0.000000E+000
|RECORD=2|OwnerIndex=2411|OwnerPartId=1|FormalType=1|PinConglomerate=56|PinLength=30|Location.X=1250|Location.Y=238|Name=54|Designator=A-54|PinPropagationDelay=0.000000E+000
|RECORD=2|OwnerIndex=2411|OwnerPartId=1|FormalType=1|PinConglomerate=58|PinLength=30|Location.X=1190|Location.Y=228|Name=55|Designator=A-55|PinPropagationDelay=0.000000E+000
|RECORD=2|OwnerIndex=2411|OwnerPartId=1|FormalType=1|PinConglomerate=56|PinLength=30|Location.X=1250|Location.Y=228|Name=56|Designator=A-56|PinPropagationDelay=0.000000E+000
|RECORD=2|OwnerIndex=2411|OwnerPartId=1|FormalType=1|PinConglomerate=58|PinLength=30|Location.X=1190|Location.Y=218|Name=57|Designator=A-57|PinPropagationDelay=0.000000E+000
|RECORD=2|OwnerIndex=2411|OwnerPartId=1|FormalType=1|PinConglomerate=56|PinLength=30|Location.X=1250|Location.Y=218|Name=58|Designator=A-58|PinPropagationDelay=0.000000E+000
|RECORD=2|OwnerIndex=2411|OwnerPartId=1|FormalType=1|PinConglomerate=58|PinLength=30|Location.X=1190|Location.Y=208|Name=59|Designator=A-59|PinPropagationDelay=0.000000E+000
|RECORD=2|OwnerIndex=2411|OwnerPartId=1|FormalType=1|PinConglomerate=56|PinLength=30|Location.X=1250|Location.Y=208|Name=60|Designator=A-60|PinPropagationDelay=0.000000E+000
|RECORD=2|OwnerIndex=2411|OwnerPartId=1|FormalType=1|PinConglomerate=58|PinLength=30|Location.X=1190|Location.Y=198|Name=61|Designator=A-61|PinPropagationDelay=0.000000E+000
|RECORD=2|OwnerIndex=2411|OwnerPartId=1|FormalType=1|PinConglomerate=56|PinLength=30|Location.X=1250|Location.Y=198|Name=62|Designator=A-62|PinPropagationDelay=0.000000E+000
|RECORD=2|OwnerIndex=2411|OwnerPartId=1|FormalType=1|PinConglomerate=58|PinLength=30|Location.X=1190|Location.Y=188|Name=63|Designator=A-63|PinPropagationDelay=0.000000E+000
|RECORD=2|OwnerIndex=2411|OwnerPartId=1|FormalType=1|PinConglomerate=56|PinLength=30|Location.X=1250|Location.Y=188|Name=64|Designator=A-64|PinPropagationDelay=0.000000E+000
|RECORD=2|OwnerIndex=2411|OwnerPartId=1|FormalType=1|PinConglomerate=58|PinLength=30|Location.X=1190|Location.Y=178|Name=65|Designator=A-65|PinPropagationDelay=0.000000E+000
|RECORD=2|OwnerIndex=2411|OwnerPartId=1|FormalType=1|PinConglomerate=56|PinLength=30|Location.X=1250|Location.Y=178|Name=66|Designator=A-66|PinPropagationDelay=0.000000E+000
|RECORD=2|OwnerIndex=2411|OwnerPartId=1|FormalType=1|PinConglomerate=58|PinLength=30|Location.X=1190|Location.Y=168|Name=67|Designator=A-67|PinPropagationDelay=0.000000E+000
|RECORD=2|OwnerIndex=2411|OwnerPartId=1|FormalType=1|PinConglomerate=56|PinLength=30|Location.X=1250|Location.Y=168|Name=68|Designator=A-68|PinPropagationDelay=0.000000E+000
|RECORD=2|OwnerIndex=2411|OwnerPartId=1|FormalType=1|PinConglomerate=58|PinLength=30|Location.X=1190|Location.Y=158|Name=69|Designator=A-69|PinPropagationDelay=0.000000E+000
|RECORD=2|OwnerIndex=2411|OwnerPartId=1|FormalType=1|PinConglomerate=56|PinLength=30|Location.X=1250|Location.Y=158|Name=70|Designator=A-70|PinPropagationDelay=0.000000E+000
|RECORD=2|OwnerIndex=2411|OwnerPartId=1|FormalType=1|PinConglomerate=58|PinLength=30|Location.X=1190|Location.Y=148|Name=71|Designator=A-71|PinPropagationDelay=0.000000E+000
|RECORD=2|OwnerIndex=2411|OwnerPartId=1|FormalType=1|PinConglomerate=56|PinLength=30|Location.X=1250|Location.Y=148|Name=72|Designator=A-72|PinPropagationDelay=0.000000E+000
|RECORD=2|OwnerIndex=2411|OwnerPartId=1|FormalType=1|PinConglomerate=58|PinLength=30|Location.X=1190|Location.Y=138|Name=73|Designator=A-73|PinPropagationDelay=0.000000E+000
|RECORD=2|OwnerIndex=2411|OwnerPartId=1|FormalType=1|PinConglomerate=56|PinLength=30|Location.X=1250|Location.Y=138|Name=74|Designator=A-74|PinPropagationDelay=0.000000E+000
|RECORD=2|OwnerIndex=2411|OwnerPartId=1|FormalType=1|PinConglomerate=58|PinLength=30|Location.X=1190|Location.Y=128|Name=75|Designator=A-75|PinPropagationDelay=0.000000E+000
|RECORD=2|OwnerIndex=2411|OwnerPartId=1|FormalType=1|PinConglomerate=56|PinLength=30|Location.X=1250|Location.Y=128|Name=76|Designator=A-76|PinPropagationDelay=0.000000E+000
|RECORD=2|OwnerIndex=2411|OwnerPartId=1|FormalType=1|PinConglomerate=58|PinLength=30|Location.X=1190|Location.Y=118|Name=77|Designator=A-77|PinPropagationDelay=0.000000E+000
|RECORD=2|OwnerIndex=2411|OwnerPartId=1|FormalType=1|PinConglomerate=56|PinLength=30|Location.X=1250|Location.Y=118|Name=78|Designator=A-78|PinPropagationDelay=0.000000E+000
|RECORD=2|OwnerIndex=2411|OwnerPartId=1|FormalType=1|PinConglomerate=58|PinLength=30|Location.X=1190|Location.Y=108|Name=79|Designator=A-79|PinPropagationDelay=0.000000E+000
|RECORD=2|OwnerIndex=2411|OwnerPartId=1|FormalType=1|PinConglomerate=56|PinLength=30|Location.X=1250|Location.Y=108|Name=80|Designator=A-80|PinPropagationDelay=0.000000E+000
|RECORD=2|OwnerIndex=2411|OwnerPartId=1|FormalType=1|PinConglomerate=58|PinLength=30|Location.X=1190|Location.Y=98|Name=81|Designator=A-81|PinPropagationDelay=0.000000E+000
|RECORD=2|OwnerIndex=2411|OwnerPartId=1|FormalType=1|PinConglomerate=56|PinLength=30|Location.X=1250|Location.Y=98|Name=82|Designator=A-82|PinPropagationDelay=0.000000E+000
|RECORD=2|OwnerIndex=2411|OwnerPartId=1|FormalType=1|PinConglomerate=58|PinLength=30|Location.X=1190|Location.Y=88|Name=83|Designator=A-83|PinPropagationDelay=0.000000E+000
|RECORD=2|OwnerIndex=2411|OwnerPartId=1|FormalType=1|PinConglomerate=56|PinLength=30|Location.X=1250|Location.Y=88|Name=84|Designator=A-84|PinPropagationDelay=0.000000E+000
|RECORD=34|OwnerIndex=2411|IndexInSheet=-1|OwnerPartId=-1|Location.X=1190|Location.Y=508|Color=8388608|FontID=1|Text=P1|Name=Designator|ReadOnlyState=1
|RECORD=41|OwnerIndex=2411|IndexInSheet=-1|OwnerPartId=-1|Location.X=1190|Location.Y=68|Color=8388608|FontID=1|Text=FPGA_CONN|Name=Comment
|RECORD=44|OwnerIndex=2411
|RECORD=45|OwnerIndex=3090|IndexInSheet=-1|ModelName=FPGA_CONN|ModelType=PCBLIB|DatafileCount=1|ModelDatafileEntity0=FPGA_CONN|ModelDatafileKind0=PCBLib|IsCurrent=T
|RECORD=46|OwnerIndex=3091
|RECORD=48|OwnerIndex=3091
|RECORD=17|IndexInSheet=337|OwnerPartId=-1|ShowNetName=T|Location.X=640|Location.Y=778|Color=255|FontID=1|Text=EXT_EEPROM_WP|IsCrossSheetConnector=T
|RECORD=27|IndexInSheet=338|OwnerPartId=-1|LineWidth=1|Color=8388608|LocationCount=3|X1=1170|Y1=828|X2=1080|Y2=828|X3=1060|Y3=828
|RECORD=27|IndexInSheet=339|OwnerPartId=-1|LineWidth=1|Color=8388608|LocationCount=3|X1=960|Y1=798|X2=1080|Y2=798|X3=1080|Y3=788
|RECORD=27|IndexInSheet=340|OwnerPartId=-1|LineWidth=1|Color=8388608|LocationCount=2|X1=320|Y1=108|X2=460|Y2=108
|RECORD=27|IndexInSheet=341|OwnerPartId=-1|LineWidth=1|Color=8388608|LocationCount=2|X1=320|Y1=118|X2=460|Y2=118
|RECORD=27|IndexInSheet=342|OwnerPartId=-1|LineWidth=1|Color=8388608|LocationCount=2|X1=320|Y1=248|X2=460|Y2=248
|RECORD=27|IndexInSheet=343|OwnerPartId=-1|LineWidth=1|Color=8388608|LocationCount=2|X1=320|Y1=318|X2=460|Y2=318
|RECORD=27|IndexInSheet=344|OwnerPartId=-1|LineWidth=1|Color=8388608|LocationCount=2|X1=320|Y1=348|X2=460|Y2=348
|RECORD=27|IndexInSheet=345|OwnerPartId=-1|LineWidth=1|Color=8388608|LocationCount=2|X1=320|Y1=388|X2=460|Y2=388
|RECORD=27|IndexInSheet=346|OwnerPartId=-1|LineWidth=1|Color=8388608|LocationCount=2|X1=320|Y1=398|X2=460|Y2=398
|RECORD=27|IndexInSheet=347|OwnerPartId=-1|LineWidth=1|Color=8388608|LocationCount=2|X1=320|Y1=498|X2=460|Y2=498
|RECORD=27|IndexInSheet=348|OwnerPartId=-1|LineWidth=1|Color=8388608|LocationCount=2|X1=460|Y1=608|X2=330|Y2=608
|RECORD=27|IndexInSheet=349|OwnerPartId=-1|LineWidth=1|Color=8388608|LocationCount=2|X1=460|Y1=618|X2=330|Y2=618
|RECORD=27|IndexInSheet=350|OwnerPartId=-1|LineWidth=1|Color=8388608|LocationCount=2|X1=460|Y1=628|X2=330|Y2=628
|RECORD=27|IndexInSheet=351|OwnerPartId=-1|LineWidth=1|Color=8388608|LocationCount=2|X1=460|Y1=638|X2=330|Y2=638
|RECORD=27|IndexInSheet=352|OwnerPartId=-1|LineWidth=1|Color=8388608|LocationCount=2|X1=460|Y1=658|X2=330|Y2=658
|RECORD=27|IndexInSheet=353|OwnerPartId=-1|LineWidth=1|Color=8388608|LocationCount=2|X1=330|Y1=768|X2=460|Y2=768
|RECORD=27|IndexInSheet=354|OwnerPartId=-1|LineWidth=1|Color=8388608|LocationCount=2|X1=330|Y1=778|X2=460|Y2=778
|RECORD=27|IndexInSheet=355|OwnerPartId=-1|LineWidth=1|Color=8388608|LocationCount=2|X1=330|Y1=818|X2=460|Y2=818
|RECORD=27|IndexInSheet=356|OwnerPartId=-1|LineWidth=1|Color=8388608|LocationCount=2|X1=460|Y1=858|X2=330|Y2=858
|RECORD=27|IndexInSheet=357|OwnerPartId=-1|LineWidth=1|Color=8388608|LocationCount=2|X1=460|Y1=868|X2=330|Y2=868
|RECORD=27|IndexInSheet=358|OwnerPartId=-1|LineWidth=1|Color=8388608|LocationCount=2|X1=460|Y1=878|X2=330|Y2=878
|RECORD=27|IndexInSheet=359|OwnerPartId=-1|LineWidth=1|Color=8388608|LocationCount=2|X1=460|Y1=888|X2=330|Y2=888
|RECORD=27|IndexInSheet=360|OwnerPartId=-1|LineWidth=1|Color=8388608|LocationCount=2|X1=460|Y1=158|X2=400|Y2=158
|RECORD=27|IndexInSheet=361|OwnerPartId=-1|LineWidth=1|Color=8388608|LocationCount=2|X1=460|Y1=208|X2=400|Y2=208
|RECORD=27|IndexInSheet=362|OwnerPartId=-1|LineWidth=1|Color=8388608|LocationCount=2|X1=460|Y1=258|X2=400|Y2=258
|RECORD=27|IndexInSheet=363|OwnerPartId=-1|LineWidth=1|Color=8388608|LocationCount=2|X1=460|Y1=308|X2=400|Y2=308
|RECORD=27|IndexInSheet=364|OwnerPartId=-1|LineWidth=1|Color=8388608|LocationCount=2|X1=460|Y1=358|X2=400|Y2=358
|RECORD=27|IndexInSheet=365|OwnerPartId=-1|LineWidth=1|Color=8388608|LocationCount=2|X1=460|Y1=408|X2=400|Y2=408
|RECORD=27|IndexInSheet=366|OwnerPartId=-1|LineWidth=1|Color=8388608|LocationCount=9|X1=460|Y1=458|X2=400|Y2=458|X3=400|Y3=408|X4=400|Y4=358|X5=400|Y5=308|X6=400|Y6=258|X7=400|Y7=208|X8=400|Y8=158|X9=400|Y9=68
|RECORD=27|IndexInSheet=367|OwnerPartId=-1|LineWidth=1|Color=8388608|LocationCount=2|X1=460|Y1=648|X2=410|Y2=648
|RECORD=27|IndexInSheet=368|OwnerPartId=-1|LineWidth=1|Color=8388608|LocationCount=2|X1=460|Y1=698|X2=410|Y2=698
|RECORD=27|IndexInSheet=369|OwnerPartId=-1|LineWidth=1|Color=8388608|LocationCount=2|X1=460|Y1=748|X2=410|Y2=748
|RECORD=27|IndexInSheet=370|OwnerPartId=-1|LineWidth=1|Color=8388608|LocationCount=2|X1=460|Y1=798|X2=410|Y2=798
|RECORD=27|IndexInSheet=371|OwnerPartId=-1|LineWidth=1|Color=8388608|LocationCount=2|X1=460|Y1=848|X2=410|Y2=848
|RECORD=27|IndexInSheet=372|OwnerPartId=-1|LineWidth=1|Color=8388608|LocationCount=2|X1=460|Y1=898|X2=410|Y2=898
|RECORD=27|IndexInSheet=373|OwnerPartId=-1|LineWidth=1|Color=8388608|LocationCount=9|X1=460|Y1=948|X2=410|Y2=948|X3=410|Y3=898|X4=410|Y4=848|X5=410|Y5=798|X6=410|Y6=748|X7=410|Y7=698|X8=410|Y8=648|X9=410|Y9=568
|RECORD=27|IndexInSheet=374|OwnerPartId=-1|LineWidth=1|Color=8388608|LocationCount=6|X1=460|Y1=958|X2=410|Y2=958|X3=410|Y3=968|X4=410|Y4=978|X5=410|Y5=988|X6=410|Y6=1008
|RECORD=27|IndexInSheet=375|OwnerPartId=-1|LineWidth=1|Color=8388608|LocationCount=2|X1=460|Y1=968|X2=410|Y2=968
|RECORD=27|IndexInSheet=376|OwnerPartId=-1|LineWidth=1|Color=8388608|LocationCount=2|X1=460|Y1=978|X2=410|Y2=978
|RECORD=27|IndexInSheet=377|OwnerPartId=-1|LineWidth=1|Color=8388608|LocationCount=2|X1=460|Y1=988|X2=410|Y2=988
|RECORD=27|IndexInSheet=378|OwnerPartId=-1|LineWidth=1|Color=8388608|LocationCount=2|X1=580|Y1=108|X2=690|Y2=108
|RECORD=27|IndexInSheet=379|OwnerPartId=-1|LineWidth=1|Color=8388608|LocationCount=2|X1=580|Y1=118|X2=690|Y2=118
|RECORD=27|IndexInSheet=380|OwnerPartId=-1|LineWidth=1|Color=8388608|LocationCount=2|X1=580|Y1=158|X2=620|Y2=158
|RECORD=27|IndexInSheet=381|OwnerPartId=-1|LineWidth=1|Color=8388608|LocationCount=2|X1=580|Y1=208|X2=620|Y2=208
|RECORD=27|IndexInSheet=382|OwnerPartId=-1|LineWidth=1|Color=8388608|LocationCount=2|X1=580|Y1=258|X2=620|Y2=258
|RECORD=27|IndexInSheet=383|OwnerPartId=-1|LineWidth=1|Color=8388608|LocationCount=2|X1=580|Y1=308|X2=620|Y2=308
|RECORD=27|IndexInSheet=384|OwnerPartId=-1|LineWidth=1|Color=8388608|LocationCount=2|X1=580|Y1=358|X2=620|Y2=358
|RECORD=27|IndexInSheet=385|OwnerPartId=-1|LineWidth=1|Color=8388608|LocationCount=2|X1=580|Y1=408|X2=620|Y2=408
|RECORD=27|IndexInSheet=386|OwnerPartId=-1|LineWidth=1|Color=8388608|LocationCount=2|X1=690|Y1=498|X2=580|Y2=498
|RECORD=27|IndexInSheet=387|OwnerPartId=-1|LineWidth=1|Color=8388608|LocationCount=2|X1=580|Y1=648|X2=600|Y2=648
|RECORD=27|IndexInSheet=388|OwnerPartId=-1|LineWidth=1|Color=8388608|LocationCount=2|X1=640|Y1=678|X2=580|Y2=678
|RECORD=27|IndexInSheet=389|OwnerPartId=-1|LineWidth=1|Color=8388608|LocationCount=2|X1=640|Y1=688|X2=580|Y2=688
|RECORD=27|IndexInSheet=390|OwnerPartId=-1|LineWidth=1|Color=8388608|LocationCount=2|X1=580|Y1=698|X2=600|Y2=698
|RECORD=27|IndexInSheet=391|OwnerPartId=-1|LineWidth=1|Color=8388608|LocationCount=2|X1=640|Y1=718|X2=580|Y2=718
|RECORD=27|IndexInSheet=392|OwnerPartId=-1|LineWidth=1|Color=8388608|LocationCount=2|X1=640|Y1=728|X2=580|Y2=728
|RECORD=27|IndexInSheet=393|OwnerPartId=-1|LineWidth=1|Color=8388608|LocationCount=2|X1=580|Y1=748|X2=600|Y2=748
|RECORD=27|IndexInSheet=394|OwnerPartId=-1|LineWidth=1|Color=8388608|LocationCount=2|X1=640|Y1=758|X2=580|Y2=758
|RECORD=27|IndexInSheet=395|OwnerPartId=-1|LineWidth=1|Color=8388608|LocationCount=2|X1=640|Y1=768|X2=580|Y2=768
|RECORD=27|IndexInSheet=396|OwnerPartId=-1|LineWidth=1|Color=8388608|LocationCount=2|X1=580|Y1=798|X2=600|Y2=798
|RECORD=27|IndexInSheet=397|OwnerPartId=-1|LineWidth=1|Color=8388608|LocationCount=2|X1=640|Y1=828|X2=580|Y2=828
|RECORD=27|IndexInSheet=398|OwnerPartId=-1|LineWidth=1|Color=8388608|LocationCount=2|X1=640|Y1=838|X2=580|Y2=838
|RECORD=27|IndexInSheet=399|OwnerPartId=-1|LineWidth=1|Color=8388608|LocationCount=2|X1=580|Y1=848|X2=600|Y2=848
|RECORD=27|IndexInSheet=400|OwnerPartId=-1|LineWidth=1|Color=8388608|LocationCount=2|X1=640|Y1=888|X2=580|Y2=888
|RECORD=27|IndexInSheet=401|OwnerPartId=-1|LineWidth=1|Color=8388608|LocationCount=2|X1=580|Y1=898|X2=600|Y2=898
|RECORD=27|IndexInSheet=402|OwnerPartId=-1|LineWidth=1|Color=8388608|LocationCount=2|X1=580|Y1=968|X2=600|Y2=968
|RECORD=27|IndexInSheet=403|OwnerPartId=-1|LineWidth=1|Color=8388608|LocationCount=2|X1=580|Y1=978|X2=600|Y2=978
|RECORD=27|IndexInSheet=404|OwnerPartId=-1|LineWidth=1|Color=8388608|LocationCount=2|X1=580|Y1=988|X2=600|Y2=988
|RECORD=27|IndexInSheet=405|OwnerPartId=-1|LineWidth=1|Color=8388608|LocationCount=3|X1=960|Y1=748|X2=1080|Y2=748|X3=1080|Y3=768
|RECORD=27|IndexInSheet=406|OwnerPartId=-1|LineWidth=1|Color=8388608|LocationCount=2|X1=1160|Y1=318|X2=1060|Y2=318
|RECORD=27|IndexInSheet=407|OwnerPartId=-1|LineWidth=1|Color=8388608|LocationCount=2|X1=1160|Y1=328|X2=1060|Y2=328
|RECORD=27|IndexInSheet=408|OwnerPartId=-1|LineWidth=1|Color=8388608|LocationCount=2|X1=1160|Y1=348|X2=1060|Y2=348
|RECORD=27|IndexInSheet=409|OwnerPartId=-1|LineWidth=1|Color=8388608|LocationCount=2|X1=1160|Y1=358|X2=1060|Y2=358
|RECORD=27|IndexInSheet=410|OwnerPartId=-1|LineWidth=1|Color=8388608|LocationCount=2|X1=1160|Y1=378|X2=1060|Y2=378
|RECORD=27|IndexInSheet=411|OwnerPartId=-1|LineWidth=1|Color=8388608|LocationCount=2|X1=1160|Y1=388|X2=1060|Y2=388
|RECORD=27|IndexInSheet=412|OwnerPartId=-1|LineWidth=1|Color=8388608|LocationCount=2|X1=1160|Y1=408|X2=1060|Y2=408
|RECORD=27|IndexInSheet=413|OwnerPartId=-1|LineWidth=1|Color=8388608|LocationCount=2|X1=1160|Y1=418|X2=1060|Y2=418
|RECORD=27|IndexInSheet=414|OwnerPartId=-1|LineWidth=1|Color=8388608|LocationCount=2|X1=1170|Y1=598|X2=1060|Y2=598
|RECORD=27|IndexInSheet=415|OwnerPartId=-1|LineWidth=1|Color=8388608|LocationCount=2|X1=1060|Y1=608|X2=1170|Y2=608
|RECORD=27|IndexInSheet=416|OwnerPartId=-1|LineWidth=1|Color=8388608|LocationCount=2|X1=1060|Y1=638|X2=1170|Y2=638
|RECORD=27|IndexInSheet=417|OwnerPartId=-1|LineWidth=1|Color=8388608|LocationCount=2|X1=1060|Y1=658|X2=1170|Y2=658
|RECORD=27|IndexInSheet=418|OwnerPartId=-1|LineWidth=1|Color=8388608|LocationCount=2|X1=1060|Y1=688|X2=1170|Y2=688
|RECORD=27|IndexInSheet=419|OwnerPartId=-1|LineWidth=1|Color=8388608|LocationCount=2|X1=1060|Y1=728|X2=1170|Y2=728
|RECORD=27|IndexInSheet=420|OwnerPartId=-1|LineWidth=1|Color=8388608|LocationCount=2|X1=1060|Y1=738|X2=1170|Y2=738
|RECORD=27|IndexInSheet=421|OwnerPartId=-1|LineWidth=1|Color=8388608|LocationCount=2|X1=1060|Y1=758|X2=1170|Y2=758
|RECORD=27|IndexInSheet=422|OwnerPartId=-1|LineWidth=1|Color=8388608|LocationCount=3|X1=1060|Y1=768|X2=1080|Y2=768|X3=1170|Y3=768
|RECORD=27|IndexInSheet=423|OwnerPartId=-1|LineWidth=1|Color=8388608|LocationCount=2|X1=1060|Y1=778|X2=1170|Y2=778
|RECORD=27|IndexInSheet=424|OwnerPartId=-1|LineWidth=1|Color=8388608|LocationCount=3|X1=1060|Y1=788|X2=1080|Y2=788|X3=1170|Y3=788
|RECORD=27|IndexInSheet=425|OwnerPartId=-1|LineWidth=1|Color=8388608|LocationCount=2|X1=1170|Y1=808|X2=1060|Y2=808
|RECORD=27|IndexInSheet=426|OwnerPartId=-1|LineWidth=1|Color=8388608|LocationCount=2|X1=1170|Y1=818|X2=1060|Y2=818
|RECORD=27|IndexInSheet=427|OwnerPartId=-1|LineWidth=1|Color=8388608|LocationCount=2|X1=1060|Y1=858|X2=1170|Y2=858
|RECORD=27|IndexInSheet=428|OwnerPartId=-1|LineWidth=1|Color=8388608|LocationCount=2|X1=1060|Y1=868|X2=1170|Y2=868
|RECORD=27|IndexInSheet=429|OwnerPartId=-1|LineWidth=1|Color=8388608|LocationCount=2|X1=1060|Y1=878|X2=1170|Y2=878
|RECORD=27|IndexInSheet=430|OwnerPartId=-1|LineWidth=1|Color=8388608|LocationCount=2|X1=1060|Y1=888|X2=1170|Y2=888
|RECORD=27|IndexInSheet=431|OwnerPartId=-1|LineWidth=1|Color=8388608|LocationCount=3|X1=1060|Y1=938|X2=1160|Y2=938|X3=1170|Y3=938
|RECORD=27|IndexInSheet=432|OwnerPartId=-1|LineWidth=1|Color=8388608|LocationCount=2|X1=1160|Y1=158|X2=1110|Y2=158
|RECORD=27|IndexInSheet=433|OwnerPartId=-1|LineWidth=1|Color=8388608|LocationCount=2|X1=1160|Y1=208|X2=1110|Y2=208
|RECORD=27|IndexInSheet=434|OwnerPartId=-1|LineWidth=1|Color=8388608|LocationCount=2|X1=1160|Y1=258|X2=1110|Y2=258
|RECORD=27|IndexInSheet=435|OwnerPartId=-1|LineWidth=1|Color=8388608|LocationCount=2|X1=1160|Y1=308|X2=1110|Y2=308
|RECORD=27|IndexInSheet=436|OwnerPartId=-1|LineWidth=1|Color=8388608|LocationCount=2|X1=1160|Y1=338|X2=1110|Y2=338
|RECORD=27|IndexInSheet=437|OwnerPartId=-1|LineWidth=1|Color=8388608|LocationCount=2|X1=1160|Y1=368|X2=1110|Y2=368
|RECORD=27|IndexInSheet=438|OwnerPartId=-1|LineWidth=1|Color=8388608|LocationCount=2|X1=1160|Y1=398|X2=1110|Y2=398
|RECORD=27|IndexInSheet=439|OwnerPartId=-1|LineWidth=1|Color=8388608|LocationCount=2|X1=1160|Y1=428|X2=1110|Y2=428
|RECORD=27|IndexInSheet=440|OwnerPartId=-1|LineWidth=1|Color=8388608|LocationCount=11|X1=1160|Y1=458|X2=1110|Y2=458|X3=1110|Y3=428|X4=1110|Y4=398|X5=1110|Y5=368|X6=1110|Y6=338|X7=1110|Y7=308|X8=1110|Y8=258|X9=1110|Y9=208|X10=1110|Y10=158|X11=1110|Y11=78
|RECORD=27|IndexInSheet=441|OwnerPartId=-1|LineWidth=1|Color=8388608|LocationCount=2|X1=1170|Y1=648|X2=1130|Y2=648
|RECORD=27|IndexInSheet=442|OwnerPartId=-1|LineWidth=1|Color=8388608|LocationCount=2|X1=1170|Y1=698|X2=1130|Y2=698
|RECORD=27|IndexInSheet=443|OwnerPartId=-1|LineWidth=1|Color=8388608|LocationCount=2|X1=1170|Y1=748|X2=1130|Y2=748
|RECORD=27|IndexInSheet=444|OwnerPartId=-1|LineWidth=1|Color=8388608|LocationCount=2|X1=1170|Y1=798|X2=1130|Y2=798
|RECORD=27|IndexInSheet=445|OwnerPartId=-1|LineWidth=1|Color=8388608|LocationCount=2|X1=1170|Y1=848|X2=1130|Y2=848
|RECORD=27|IndexInSheet=446|OwnerPartId=-1|LineWidth=1|Color=8388608|LocationCount=2|X1=1170|Y1=898|X2=1130|Y2=898
|RECORD=27|IndexInSheet=447|OwnerPartId=-1|LineWidth=1|Color=8388608|LocationCount=9|X1=1170|Y1=948|X2=1130|Y2=948|X3=1130|Y3=898|X4=1130|Y4=848|X5=1130|Y5=798|X6=1130|Y6=748|X7=1130|Y7=698|X8=1130|Y8=648|X9=1130|Y9=568
|RECORD=27|IndexInSheet=448|OwnerPartId=-1|LineWidth=1|Color=8388608|LocationCount=3|X1=1170|Y1=928|X2=1160|Y2=928|X3=1160|Y3=938
|RECORD=27|IndexInSheet=449|OwnerPartId=-1|LineWidth=1|Color=8388608|LocationCount=2|X1=1280|Y1=158|X2=1310|Y2=158
|RECORD=27|IndexInSheet=450|OwnerPartId=-1|LineWidth=1|Color=8388608|LocationCount=2|X1=1280|Y1=208|X2=1310|Y2=208
|RECORD=27|IndexInSheet=451|OwnerPartId=-1|LineWidth=1|Color=8388608|LocationCount=2|X1=1280|Y1=258|X2=1310|Y2=258
|RECORD=27|IndexInSheet=452|OwnerPartId=-1|LineWidth=1|Color=8388608|LocationCount=2|X1=1280|Y1=308|X2=1310|Y2=308
|RECORD=27|IndexInSheet=453|OwnerPartId=-1|LineWidth=1|Color=8388608|LocationCount=2|X1=1280|Y1=318|X2=1360|Y2=318
|RECORD=27|IndexInSheet=454|OwnerPartId=-1|LineWidth=1|Color=8388608|LocationCount=2|X1=1280|Y1=328|X2=1360|Y2=328
|RECORD=27|IndexInSheet=455|OwnerPartId=-1|LineWidth=1|Color=8388608|LocationCount=2|X1=1280|Y1=348|X2=1360|Y2=348
|RECORD=27|IndexInSheet=456|OwnerPartId=-1|LineWidth=1|Color=8388608|LocationCount=2|X1=1280|Y1=358|X2=1360|Y2=358
|RECORD=27|IndexInSheet=457|OwnerPartId=-1|LineWidth=1|Color=8388608|LocationCount=2|X1=1280|Y1=378|X2=1360|Y2=378
|RECORD=27|IndexInSheet=458|OwnerPartId=-1|LineWidth=1|Color=8388608|LocationCount=2|X1=1280|Y1=388|X2=1360|Y2=388
|RECORD=27|IndexInSheet=459|OwnerPartId=-1|LineWidth=1|Color=8388608|LocationCount=2|X1=1280|Y1=408|X2=1360|Y2=408
|RECORD=27|IndexInSheet=460|OwnerPartId=-1|LineWidth=1|Color=8388608|LocationCount=2|X1=1280|Y1=418|X2=1360|Y2=418
|RECORD=27|IndexInSheet=461|OwnerPartId=-1|LineWidth=1|Color=8388608|LocationCount=2|X1=1280|Y1=438|X2=1360|Y2=438
|RECORD=27|IndexInSheet=462|OwnerPartId=-1|LineWidth=1|Color=8388608|LocationCount=2|X1=1280|Y1=448|X2=1360|Y2=448
|RECORD=27|IndexInSheet=463|OwnerPartId=-1|LineWidth=1|Color=8388608|LocationCount=2|X1=1290|Y1=648|X2=1320|Y2=648
|RECORD=27|IndexInSheet=464|OwnerPartId=-1|LineWidth=1|Color=8388608|LocationCount=2|X1=1290|Y1=698|X2=1320|Y2=698
|RECORD=27|IndexInSheet=465|OwnerPartId=-1|LineWidth=1|Color=8388608|LocationCount=2|X1=1290|Y1=748|X2=1320|Y2=748
|RECORD=27|IndexInSheet=466|OwnerPartId=-1|LineWidth=1|Color=8388608|LocationCount=2|X1=1290|Y1=798|X2=1320|Y2=798
|RECORD=27|IndexInSheet=467|OwnerPartId=-1|LineWidth=1|Color=8388608|LocationCount=2|X1=1290|Y1=848|X2=1320|Y2=848
|RECORD=27|IndexInSheet=468|OwnerPartId=-1|LineWidth=1|Color=8388608|LocationCount=2|X1=1290|Y1=898|X2=1320|Y2=898
|RECORD=27|IndexInSheet=469|OwnerPartId=-1|LineWidth=1|Color=8388608|LocationCount=2|X1=1350|Y1=958|X2=1290|Y2=958
|RECORD=27|IndexInSheet=470|OwnerPartId=-1|LineWidth=1|Color=8388608|LocationCount=2|X1=1350|Y1=968|X2=1290|Y2=968
|RECORD=27|IndexInSheet=471|OwnerPartId=-1|LineWidth=1|Color=8388608|LocationCount=3|X1=960|Y1=838|X2=1080|Y2=838|X3=1080|Y3=828
|RECORD=27|IndexInSheet=472|OwnerPartId=-1|LineWidth=1|Color=8388608|LocationCount=9|X1=580|Y1=948|X2=600|Y2=948|X3=600|Y3=898|X4=600|Y4=848|X5=600|Y5=798|X6=600|Y6=748|X7=600|Y7=698|X8=600|Y8=648|X9=600|Y9=568
|RECORD=27|IndexInSheet=473|OwnerPartId=-1|LineWidth=1|Color=8388608|LocationCount=6|X1=580|Y1=958|X2=600|Y2=958|X3=600|Y3=968|X4=600|Y4=978|X5=600|Y5=988|X6=600|Y6=1008
|RECORD=27|IndexInSheet=474|OwnerPartId=-1|LineWidth=1|Color=8388608|LocationCount=2|X1=1290|Y1=598|X2=1350|Y2=598
|RECORD=27|IndexInSheet=475|OwnerPartId=-1|LineWidth=1|Color=8388608|LocationCount=2|X1=1350|Y1=628|X2=1290|Y2=628
|RECORD=27|IndexInSheet=476|OwnerPartId=-1|LineWidth=1|Color=8388608|LocationCount=2|X1=1350|Y1=638|X2=1290|Y2=638
|RECORD=27|IndexInSheet=477|OwnerPartId=-1|LineWidth=1|Color=8388608|LocationCount=2|X1=1350|Y1=678|X2=1290|Y2=678
|RECORD=27|IndexInSheet=478|OwnerPartId=-1|LineWidth=1|Color=8388608|LocationCount=2|X1=1290|Y1=828|X2=1350|Y2=828
|RECORD=27|IndexInSheet=479|OwnerPartId=-1|LineWidth=1|Color=8388608|LocationCount=2|X1=1350|Y1=858|X2=1290|Y2=858
|RECORD=27|IndexInSheet=480|OwnerPartId=-1|LineWidth=1|Color=8388608|LocationCount=2|X1=1350|Y1=868|X2=1290|Y2=868
|RECORD=27|IndexInSheet=481|OwnerPartId=-1|LineWidth=1|Color=8388608|LocationCount=2|X1=1290|Y1=918|X2=1350|Y2=918
|RECORD=27|IndexInSheet=482|OwnerPartId=-1|LineWidth=1|Color=8388608|LocationCount=9|X1=1290|Y1=948|X2=1320|Y2=948|X3=1320|Y3=898|X4=1320|Y4=848|X5=1320|Y5=798|X6=1320|Y6=748|X7=1320|Y7=698|X8=1320|Y8=648|X9=1320|Y9=568
|RECORD=27|IndexInSheet=483|OwnerPartId=-1|LineWidth=1|Color=8388608|LocationCount=9|X1=580|Y1=458|X2=620|Y2=458|X3=620|Y3=408|X4=620|Y4=358|X5=620|Y5=308|X6=620|Y6=258|X7=620|Y7=208|X8=620|Y8=158|X9=620|Y9=68
|RECORD=27|IndexInSheet=484|OwnerPartId=-1|LineWidth=1|Color=8388608|LocationCount=7|X1=1280|Y1=458|X2=1310|Y2=458|X3=1310|Y3=308|X4=1310|Y4=258|X5=1310|Y5=208|X6=1310|Y6=158|X7=1310|Y7=78
|RECORD=27|IndexInSheet=485|OwnerPartId=-1|LineWidth=1|Color=8388608|LocationCount=2|X1=640|Y1=778|X2=580|Y2=778
|RECORD=41|IndexInSheet=486|OwnerPartId=-1|Color=8388608|FontID=1|IsHidden=T|Name=ConfigurationParameters|ReadOnlyState=1
|RECORD=41|IndexInSheet=487|OwnerPartId=-1|Color=8388608|FontID=1|IsHidden=T|Name=ConfiguratorName|ReadOnlyState=1
|RECORD=41|IndexInSheet=488|OwnerPartId=-1|Color=8388608|FontID=1|IsHidden=T|Name=VersionControl_RevNumber|ReadOnlyState=1
|RECORD=41|IndexInSheet=489|OwnerPartId=-1|Color=8388608|FontID=1|IsHidden=T|Name=IsUserConfigurable|ReadOnlyState=1
|RECORD=41|IndexInSheet=490|OwnerPartId=-1|Color=8388608|FontID=1|IsHidden=T|Name=VersionControl_ProjFolderRevNumber|ReadOnlyState=1
|RECORD=41|IndexInSheet=491|OwnerPartId=-1|Color=8388608|FontID=1|IsHidden=T|Name=SPICEModelCache|ReadOnlyState=1
|RECORD=29|IndexInSheet=-1|OwnerPartId=-1|Location.X=400|Location.Y=158|Color=128
|RECORD=29|IndexInSheet=-1|OwnerPartId=-1|Location.X=400|Location.Y=208|Color=128
|RECORD=29|IndexInSheet=-1|OwnerPartId=-1|Location.X=400|Location.Y=258|Color=128
|RECORD=29|IndexInSheet=-1|OwnerPartId=-1|Location.X=400|Location.Y=308|Color=128
|RECORD=29|IndexInSheet=-1|OwnerPartId=-1|Location.X=400|Location.Y=358|Color=128
|RECORD=29|IndexInSheet=-1|OwnerPartId=-1|Location.X=400|Location.Y=408|Color=128
|RECORD=29|IndexInSheet=-1|OwnerPartId=-1|Location.X=410|Location.Y=648|Color=128
|RECORD=29|IndexInSheet=-1|OwnerPartId=-1|Location.X=410|Location.Y=698|Color=128
|RECORD=29|IndexInSheet=-1|OwnerPartId=-1|Location.X=410|Location.Y=748|Color=128
|RECORD=29|IndexInSheet=-1|OwnerPartId=-1|Location.X=410|Location.Y=798|Color=128
|RECORD=29|IndexInSheet=-1|OwnerPartId=-1|Location.X=410|Location.Y=848|Color=128
|RECORD=29|IndexInSheet=-1|OwnerPartId=-1|Location.X=410|Location.Y=898|Color=128
|RECORD=29|IndexInSheet=-1|OwnerPartId=-1|Location.X=410|Location.Y=968|Color=128
|RECORD=29|IndexInSheet=-1|OwnerPartId=-1|Location.X=410|Location.Y=978|Color=128
|RECORD=29|IndexInSheet=-1|OwnerPartId=-1|Location.X=410|Location.Y=988|Color=128
|RECORD=29|IndexInSheet=-1|OwnerPartId=-1|Location.X=600|Location.Y=648|Color=128
|RECORD=29|IndexInSheet=-1|OwnerPartId=-1|Location.X=600|Location.Y=698|Color=128
|RECORD=29|IndexInSheet=-1|OwnerPartId=-1|Location.X=600|Location.Y=748|Color=128
|RECORD=29|IndexInSheet=-1|OwnerPartId=-1|Location.X=600|Location.Y=798|Color=128
|RECORD=29|IndexInSheet=-1|OwnerPartId=-1|Location.X=600|Location.Y=848|Color=128
|RECORD=29|IndexInSheet=-1|OwnerPartId=-1|Location.X=600|Location.Y=898|Color=128
|RECORD=29|IndexInSheet=-1|OwnerPartId=-1|Location.X=600|Location.Y=968|Color=128
|RECORD=29|IndexInSheet=-1|OwnerPartId=-1|Location.X=600|Location.Y=978|Color=128
|RECORD=29|IndexInSheet=-1|OwnerPartId=-1|Location.X=600|Location.Y=988|Color=128
|RECORD=29|IndexInSheet=-1|OwnerPartId=-1|Location.X=620|Location.Y=158|Color=128
|RECORD=29|IndexInSheet=-1|OwnerPartId=-1|Location.X=620|Location.Y=208|Color=128
|RECORD=29|IndexInSheet=-1|OwnerPartId=-1|Location.X=620|Location.Y=258|Color=128
|RECORD=29|IndexInSheet=-1|OwnerPartId=-1|Location.X=620|Location.Y=308|Color=128
|RECORD=29|IndexInSheet=-1|OwnerPartId=-1|Location.X=620|Location.Y=358|Color=128
|RECORD=29|IndexInSheet=-1|OwnerPartId=-1|Location.X=620|Location.Y=408|Color=128
|RECORD=29|IndexInSheet=-1|OwnerPartId=-1|Location.X=1080|Location.Y=768|Color=128
|RECORD=29|IndexInSheet=-1|OwnerPartId=-1|Location.X=1080|Location.Y=788|Color=128
|RECORD=29|IndexInSheet=-1|OwnerPartId=-1|Location.X=1080|Location.Y=828|Color=128
|RECORD=29|IndexInSheet=-1|OwnerPartId=-1|Location.X=1110|Location.Y=158|Color=128
|RECORD=29|IndexInSheet=-1|OwnerPartId=-1|Location.X=1110|Location.Y=208|Color=128
|RECORD=29|IndexInSheet=-1|OwnerPartId=-1|Location.X=1110|Location.Y=258|Color=128
|RECORD=29|IndexInSheet=-1|OwnerPartId=-1|Location.X=1110|Location.Y=308|Color=128
|RECORD=29|IndexInSheet=-1|OwnerPartId=-1|Location.X=1110|Location.Y=338|Color=128
|RECORD=29|IndexInSheet=-1|OwnerPartId=-1|Location.X=1110|Location.Y=368|Color=128
|RECORD=29|IndexInSheet=-1|OwnerPartId=-1|Location.X=1110|Location.Y=398|Color=128
|RECORD=29|IndexInSheet=-1|OwnerPartId=-1|Location.X=1110|Location.Y=428|Color=128
|RECORD=29|IndexInSheet=-1|OwnerPartId=-1|Location.X=1130|Location.Y=648|Color=128
|RECORD=29|IndexInSheet=-1|OwnerPartId=-1|Location.X=1130|Location.Y=698|Color=128
|RECORD=29|IndexInSheet=-1|OwnerPartId=-1|Location.X=1130|Location.Y=748|Color=128
|RECORD=29|IndexInSheet=-1|OwnerPartId=-1|Location.X=1130|Location.Y=798|Color=128
|RECORD=29|IndexInSheet=-1|OwnerPartId=-1|Location.X=1130|Location.Y=848|Color=128
|RECORD=29|IndexInSheet=-1|OwnerPartId=-1|Location.X=1130|Location.Y=898|Color=128
|RECORD=29|IndexInSheet=-1|OwnerPartId=-1|Location.X=1160|Location.Y=938|Color=128
|RECORD=29|IndexInSheet=-1|OwnerPartId=-1|Location.X=1310|Location.Y=158|Color=128
|RECORD=29|IndexInSheet=-1|OwnerPartId=-1|Location.X=1310|Location.Y=208|Color=128
|RECORD=29|IndexInSheet=-1|OwnerPartId=-1|Location.X=1310|Location.Y=258|Color=128
|RECORD=29|IndexInSheet=-1|OwnerPartId=-1|Location.X=1310|Location.Y=308|Color=128
|RECORD=29|IndexInSheet=-1|OwnerPartId=-1|Location.X=1320|Location.Y=648|Color=128
|RECORD=29|IndexInSheet=-1|OwnerPartId=-1|Location.X=1320|Location.Y=698|Color=128
|RECORD=29|IndexInSheet=-1|OwnerPartId=-1|Location.X=1320|Location.Y=748|Color=128
|RECORD=29|IndexInSheet=-1|OwnerPartId=-1|Location.X=1320|Location.Y=798|Color=128
|RECORD=29|IndexInSheet=-1|OwnerPartId=-1|Location.X=1320|Location.Y=848|Color=128
|RECORD=29|IndexInSheet=-1|OwnerPartId=-1|Location.X=1320|Location.Y=898|Color=128